CONCISE NET LIST - 1  
85_10INCH_BOT_DN         J24              2        DELTA_L-DELTA-L,THLF,EMPTY,TP24
85_10INCH_BOT_DN         J27              1        DELTA_L-DELTA-L,THLF,EMPTY,TP24
85_10INCH_BOT_DP         J24              1        DELTA_L-DELTA-L,THLF,EMPTY,TP24
85_10INCH_BOT_DP         J27              2        DELTA_L-DELTA-L,THLF,EMPTY,TP24
85_10INCH_IN1_DN         J28              1        DELTA_L-DELTA-L,THLF,EMPTY,TP24
85_10INCH_IN1_DN         J30              2        DELTA_L-DELTA-L,THLF,EMPTY,TP24
85_10INCH_IN1_DP         J28              2        DELTA_L-DELTA-L,THLF,EMPTY,TP24
85_10INCH_IN1_DP         J30              1        DELTA_L-DELTA-L,THLF,EMPTY,TP24
85_10INCH_IN4_DN         J23              2        DELTA_L-DELTA-L,THLF,EMPTY,TP24
85_10INCH_IN4_DN         J26              1        DELTA_L-DELTA-L,THLF,EMPTY,TP24
85_10INCH_IN4_DP         J23              1        DELTA_L-DELTA-L,THLF,EMPTY,TP24
85_10INCH_IN4_DP         J26              2        DELTA_L-DELTA-L,THLF,EMPTY,TP24
85_10INCH_TOP_DN         J22              2        DELTA_L-DELTA-L,THLF,EMPTY,TP24
85_10INCH_TOP_DN         J25              1        DELTA_L-DELTA-L,THLF,EMPTY,TP24
85_10INCH_TOP_DP         J22              1        DELTA_L-DELTA-L,THLF,EMPTY,TP24
85_10INCH_TOP_DP         J25              2        DELTA_L-DELTA-L,THLF,EMPTY,TP24
85_5INCH_BOT_DN          J17              1        DELTA_L-DELTA-L,THLF,EMPTY,TP24
85_5INCH_BOT_DN          J20              2        DELTA_L-DELTA-L,THLF,EMPTY,TP24
85_5INCH_BOT_DP          J17              2        DELTA_L-DELTA-L,THLF,EMPTY,TP24
85_5INCH_BOT_DP          J20              1        DELTA_L-DELTA-L,THLF,EMPTY,TP24
85_5INCH_IN1_DN          J11              1        DELTA_L-DELTA-L,THLF,EMPTY,TP24
85_5INCH_IN1_DN          J29              2        DELTA_L-DELTA-L,THLF,EMPTY,TP24
85_5INCH_IN1_DP          J11              2        DELTA_L-DELTA-L,THLF,EMPTY,TP24
85_5INCH_IN1_DP          J29              1        DELTA_L-DELTA-L,THLF,EMPTY,TP24
85_5INCH_IN4_DN          J16              1        DELTA_L-DELTA-L,THLF,EMPTY,TP24
85_5INCH_IN4_DN          J19              2        DELTA_L-DELTA-L,THLF,EMPTY,TP24
85_5INCH_IN4_DP          J16              2        DELTA_L-DELTA-L,THLF,EMPTY,TP24
85_5INCH_IN4_DP          J19              1        DELTA_L-DELTA-L,THLF,EMPTY,TP24
85_5INCH_TOP_DN          J9               1        DELTA_L-DELTA-L,THLF,EMPTY,TP24
85_5INCH_TOP_DN          J12              2        DELTA_L-DELTA-L,THLF,EMPTY,TP24
85_5INCH_TOP_DP          J9               2        DELTA_L-DELTA-L,THLF,EMPTY,TP24
85_5INCH_TOP_DP          J12              1        DELTA_L-DELTA-L,THLF,EMPTY,TP24
ADCVREFEXT0              C282             1        Q_CAP_C0402-1UF,25V,10%,X6S,CHA
ADCVREFEXT0              C284             1        Q_CAP_0402-0.1UF,25V,10%,X7R,CA
ADCVREFEXT0              R780             2        Q_RES_0402LF-0,5%,1/16W,EMPTY,A
ADCVREFEXT0              R783             2        Q_RES_0402LF-0,5%,1/16W,CHIP,CA
ADCVREFEXT0              R784             2        Q_RES_0402LF-0,5%,1/16W,EMPTY,A
ADCVREFEXT0              U5               AF19     AST2600A1GP-AST2600A1-GP,SMLF,A
ADCVREFEXT1              C277             1        Q_CAP_C0402-1UF,25V,10%,X6S,CHA
ADCVREFEXT1              C279             1        Q_CAP_0402-0.1UF,25V,10%,X7R,CA
ADCVREFEXT1              R779             2        Q_RES_0402LF-0,5%,1/16W,CHIP,CA
ADCVREFEXT1              R781             2        Q_RES_0402LF-0,5%,1/16W,EMPTY,A
ADCVREFEXT1              R782             2        Q_RES_0402LF-0,5%,1/16W,EMPTY,A
ADCVREFEXT1              U5               AF17     AST2600A1GP-AST2600A1-GP,SMLF,A
A_BMC_ADCAV33            C75              1        Q_CAP_C0402-1UF,25V,10%,X6S,CHA
A_BMC_ADCAV33            C77              1        Q_CAP_0402-0.1UF,25V,10%,X7R,CA
A_BMC_ADCAV33            L12              2        Q_INDUCTOR_SMLF-BLM18PG121SN1DA
A_BMC_ADCAV33            U5               AA21     AST2600A1GP-AST2600A1-GP,SMLF,A
A_BMC_ADCAV33            U5               Y21      AST2600A1GP-AST2600A1-GP,SMLF,A
A_BMC_ADCREXT0           R233             2        Q_RES_0402LF -49.9K,1%,1/16W ,A
A_BMC_ADCREXT0           U5               AF20     AST2600A1GP-AST2600A1-GP,SMLF,A
A_BMC_ADCREXT1           R234             2        Q_RES_0402LF -49.9K,1%,1/16W ,A
A_BMC_ADCREXT1           U5               AF18     AST2600A1GP-AST2600A1-GP,SMLF,A
A_BMC_ADCVREFN0          C134             2        Q_CAP_C0402-0.01UF,50V,10%,X7RA
A_BMC_ADCVREFN0          C138             1        Q_CAP_C0402-0.01UF,50V,10%,X7RA
A_BMC_ADCVREFN0          U5               AB20     AST2600A1GP-AST2600A1-GP,SMLF,A
A_BMC_ADCVREFN1          C133             2        Q_CAP_C0402-0.01UF,50V,10%,X7RA
A_BMC_ADCVREFN1          C137             1        Q_CAP_C0402-0.01UF,50V,10%,X7RA
A_BMC_ADCVREFN1          U5               AD18     AST2600A1GP-AST2600A1-GP,SMLF,A
A_BMC_ADCVREFP0          C136             2        Q_CAP_C0402-0.01UF,50V,10%,X7RA
A_BMC_ADCVREFP0          C138             2        Q_CAP_C0402-0.01UF,50V,10%,X7RA
A_BMC_ADCVREFP0          U5               AC20     AST2600A1GP-AST2600A1-GP,SMLF,A
A_BMC_ADCVREFP1          C135             2        Q_CAP_C0402-0.01UF,50V,10%,X7RA
A_BMC_ADCVREFP1          C137             2        Q_CAP_C0402-0.01UF,50V,10%,X7RA
A_BMC_ADCVREFP1          U5               AD17     AST2600A1GP-AST2600A1-GP,SMLF,A
A_BMC_DACREST            R235             2        Q_RES_0402LF-2.74K,1%,1/16W,CHA
A_BMC_DACREST            U5               AC21     AST2600A1GP-AST2600A1-GP,SMLF,A
BATTERY_DETECT           R775             1        Q_RES_0402LF-1K,1%,1/16W,CHIP,A
BATTERY_DETECT           U5               AE15     AST2600A1GP-AST2600A1-GP,SMLF,A
BATTERY_DETECT_R         Q11              G        MOSFET_N_GSD-NX7002AK,SMLF,IC,A
BATTERY_DETECT_R         R775             2        Q_RES_0402LF-1K,1%,1/16W,CHIP,A
BATTERY_DETECT_R         R776             1        Q_RES_0201LF-47K,1%,1/20W,CHIPA
BJT_Q3_B                 Q3               B        MMBT39047F-MMBT3904-7-F,SMLF,IA
BJT_Q3_B                 R290             1        Q_RES_0402LF-47K,1%,1/16W,CHIPA
BJT_Q3_C                 Q1               B        MMBT39047F-MMBT3904-7-F,SMLF,IA
BJT_Q3_C                 Q3               C        MMBT39047F-MMBT3904-7-F,SMLF,IA
BJT_Q3_C                 R289             2        Q_RES_0402LF-10K,1%,1/16W,CHIPA
BMC_CLK_25M              R215             2        Q_RES_0402LF-33       ,1%  ,1/A
BMC_CLK_25M              U5               D10      AST2600A1GP-AST2600A1-GP,SMLF,A
BMC_CLK_25M_R            OSC1             3        OSC4_7X25000018-25MHZ,SMLF,MISA
BMC_CLK_25M_R            R215             1        Q_RES_0402LF-33       ,1%  ,1/A
BMC_CPLD_GPIO_1          R60              1        Q_RES_0402LF-33       ,1%  ,1/A
BMC_CPLD_GPIO_1          R495             1        Q_RES_0402LF-0,5%,1/16W,CHIP,CA
BMC_CPLD_GPIO_1          R581             2        Q_RES_0402LF-4.7K,5%,1/16W,CHIA
BMC_CPLD_GPIO_10         R473             2        Q_RES_0402LF-33       ,1%  ,1/A
BMC_CPLD_GPIO_10         R534             2        Q_RES_0402LF-33       ,1%  ,1/A
BMC_CPLD_GPIO_10         R605             2        Q_RES_0402LF-4.7K,5%,1/16W,CHIA
BMC_CPLD_GPIO_10_R1      R473             1        Q_RES_0402LF-33       ,1%  ,1/A
BMC_CPLD_GPIO_10_R1      U5               AF10     AST2600A1GP-AST2600A1-GP,SMLF,A
BMC_CPLD_GPIO_10_R2      R534             1        Q_RES_0402LF-33       ,1%  ,1/A
BMC_CPLD_GPIO_10_R2      U25              K8       10M02SCU169C8G-10M02SCU169C8G,A
BMC_CPLD_GPIO_11         R463             2        Q_RES_0402LF-33       ,1%  ,1/A
BMC_CPLD_GPIO_11         R535             2        Q_RES_0402LF-33       ,1%  ,1/A
BMC_CPLD_GPIO_11         R606             2        Q_RES_0402LF-4.7K,5%,1/16W,CHIA
BMC_CPLD_GPIO_11_R1      R463             1        Q_RES_0402LF-33       ,1%  ,1/A
BMC_CPLD_GPIO_11_R1      U5               F24      AST2600A1GP-AST2600A1-GP,SMLF,A
BMC_CPLD_GPIO_11_R2      R535             1        Q_RES_0402LF-33       ,1%  ,1/A
BMC_CPLD_GPIO_11_R2      U25              M10      10M02SCU169C8G-10M02SCU169C8G,A
BMC_CPLD_GPIO_12         R465             2        Q_RES_0402LF-33       ,1%  ,1/A
BMC_CPLD_GPIO_12         R536             2        Q_RES_0402LF-33       ,1%  ,1/A
BMC_CPLD_GPIO_12         R607             2        Q_RES_0402LF-4.7K,5%,1/16W,CHIA
BMC_CPLD_GPIO_12_R1      R465             1        Q_RES_0402LF-33       ,1%  ,1/A
BMC_CPLD_GPIO_12_R1      U5               D26      AST2600A1GP-AST2600A1-GP,SMLF,A
BMC_CPLD_GPIO_12_R2      R536             1        Q_RES_0402LF-33       ,1%  ,1/A
BMC_CPLD_GPIO_12_R2      U25              L10      10M02SCU169C8G-10M02SCU169C8G,A
BMC_CPLD_GPIO_13         R466             2        Q_RES_0402LF-33       ,1%  ,1/A
BMC_CPLD_GPIO_13         R537             2        Q_RES_0402LF-33       ,1%  ,1/A
BMC_CPLD_GPIO_13         R608             2        Q_RES_0402LF-4.7K,5%,1/16W,CHIA
BMC_CPLD_GPIO_13_R1      R466             1        Q_RES_0402LF-33       ,1%  ,1/A
BMC_CPLD_GPIO_13_R1      U5               D24      AST2600A1GP-AST2600A1-GP,SMLF,A
BMC_CPLD_GPIO_13_R2      R537             1        Q_RES_0402LF-33       ,1%  ,1/A
BMC_CPLD_GPIO_13_R2      U25              K10      10M02SCU169C8G-10M02SCU169C8G,A
BMC_CPLD_GPIO_14         R462             2        Q_RES_0402LF-33       ,1%  ,1/A
BMC_CPLD_GPIO_14         R540             2        Q_RES_0402LF-33       ,1%  ,1/A
BMC_CPLD_GPIO_14         R609             2        Q_RES_0402LF-4.7K,5%,1/16W,CHIA
BMC_CPLD_GPIO_14_R1      R462             1        Q_RES_0402LF-33       ,1%  ,1/A
BMC_CPLD_GPIO_14_R1      U5               T25      AST2600A1GP-AST2600A1-GP,SMLF,A
BMC_CPLD_GPIO_14_R2      R540             1        Q_RES_0402LF-33       ,1%  ,1/A
BMC_CPLD_GPIO_14_R2      U25              K11      10M02SCU169C8G-10M02SCU169C8G,A
BMC_CPLD_GPIO_15         R474             1        Q_RES_0402LF-33       ,1%  ,1/A
BMC_CPLD_GPIO_15         R541             2        Q_RES_0402LF-33       ,1%  ,1/A
BMC_CPLD_GPIO_15         R611             2        Q_RES_0402LF-4.7K,5%,1/16W,CHIA
BMC_CPLD_GPIO_15_R1      R474             2        Q_RES_0402LF-33       ,1%  ,1/A
BMC_CPLD_GPIO_15_R1      U5               AA25     AST2600A1GP-AST2600A1-GP,SMLF,A
BMC_CPLD_GPIO_15_R2      R541             1        Q_RES_0402LF-33       ,1%  ,1/A
BMC_CPLD_GPIO_15_R2      U25              J10      10M02SCU169C8G-10M02SCU169C8G,A
BMC_CPLD_GPIO_16         R475             1        Q_RES_0402LF-33       ,1%  ,1/A
BMC_CPLD_GPIO_16         R542             1        Q_RES_0402LF-0,5%,1/16W,CHIP,CA
BMC_CPLD_GPIO_16         R612             2        Q_RES_0402LF-4.7K,5%,1/16W,CHIA
BMC_CPLD_GPIO_16_R1      R475             2        Q_RES_0402LF-33       ,1%  ,1/A
BMC_CPLD_GPIO_16_R1      U5               AB25     AST2600A1GP-AST2600A1-GP,SMLF,A
BMC_CPLD_GPIO_16_R2      R542             2        Q_RES_0402LF-0,5%,1/16W,CHIP,CA
BMC_CPLD_GPIO_16_R2      U25              G9       10M02SCU169C8G-10M02SCU169C8G,A
BMC_CPLD_GPIO_17         R476             1        Q_RES_0402LF-33       ,1%  ,1/A
BMC_CPLD_GPIO_17         R572             1        Q_RES_0402LF-0,5%,1/16W,CHIP,CA
BMC_CPLD_GPIO_17         R613             2        Q_RES_0402LF-4.7K,5%,1/16W,CHIA
BMC_CPLD_GPIO_17_R1      R476             2        Q_RES_0402LF-33       ,1%  ,1/A
BMC_CPLD_GPIO_17_R1      U5               Y24      AST2600A1GP-AST2600A1-GP,SMLF,A
BMC_CPLD_GPIO_17_R2      R572             2        Q_RES_0402LF-0,5%,1/16W,CHIP,CA
BMC_CPLD_GPIO_17_R2      U25              G10      10M02SCU169C8G-10M02SCU169C8G,A
BMC_CPLD_GPIO_18         R477             1        Q_RES_0402LF-33       ,1%  ,1/A
BMC_CPLD_GPIO_18         R573             1        Q_RES_0402LF-0,5%,1/16W,CHIP,CA
BMC_CPLD_GPIO_18         R617             2        Q_RES_0402LF-4.7K,5%,1/16W,CHIA
BMC_CPLD_GPIO_18_R1      R477             2        Q_RES_0402LF-33       ,1%  ,1/A
BMC_CPLD_GPIO_18_R1      U5               AB26     AST2600A1GP-AST2600A1-GP,SMLF,A
BMC_CPLD_GPIO_18_R2      R573             2        Q_RES_0402LF-0,5%,1/16W,CHIP,CA
BMC_CPLD_GPIO_18_R2      U25              F13      10M02SCU169C8G-10M02SCU169C8G,A
BMC_CPLD_GPIO_19_R1      R478             2        Q_RES_0402LF-33       ,1%  ,1/A
BMC_CPLD_GPIO_19_R1      U5               Y26      AST2600A1GP-AST2600A1-GP,SMLF,A
BMC_CPLD_GPIO_19_R2      R574             2        Q_RES_0402LF-0,5%,1/16W,CHIP,CA
BMC_CPLD_GPIO_19_R2      U25              E13      10M02SCU169C8G-10M02SCU169C8G,A
BMC_CPLD_GPIO_1_R1       R60              2        Q_RES_0402LF-33       ,1%  ,1/A
BMC_CPLD_GPIO_1_R1       U5               C22      AST2600A1GP-AST2600A1-GP,SMLF,A
BMC_CPLD_GPIO_1_R2       R495             2        Q_RES_0402LF-0,5%,1/16W,CHIP,CA
BMC_CPLD_GPIO_1_R2       U25              E1       10M02SCU169C8G-10M02SCU169C8G,A
BMC_CPLD_GPIO_2          R65              1        Q_RES_0402LF-33       ,1%  ,1/A
BMC_CPLD_GPIO_2          R519             1        Q_RES_0402LF-0,5%,1/16W,CHIP,CA
BMC_CPLD_GPIO_2          R586             2        Q_RES_0402LF-4.7K,5%,1/16W,CHIA
BMC_CPLD_GPIO_19         R478             1        Q_RES_0402LF-33       ,1%  ,1/A
BMC_CPLD_GPIO_19         R574             1        Q_RES_0402LF-0,5%,1/16W,CHIP,CA
BMC_CPLD_GPIO_19         R619             2        Q_RES_0402LF-4.7K,5%,1/16W,CHIA
BMC_CPLD_GPIO_20         R479             1        Q_RES_0402LF-33       ,1%  ,1/A
BMC_CPLD_GPIO_20         R575             1        Q_RES_0402LF-0,5%,1/16W,CHIP,CA
BMC_CPLD_GPIO_20         R621             2        Q_RES_0402LF-4.7K,5%,1/16W,CHIA
BMC_CPLD_GPIO_20_R1      R479             2        Q_RES_0402LF-33       ,1%  ,1/A
BMC_CPLD_GPIO_20_R1      U5               AC26     AST2600A1GP-AST2600A1-GP,SMLF,A
BMC_CPLD_GPIO_20_R2      R575             2        Q_RES_0402LF-0,5%,1/16W,CHIP,CA
BMC_CPLD_GPIO_20_R2      U25              F12      10M02SCU169C8G-10M02SCU169C8G,A
BMC_CPLD_GPIO_21         R480             1        Q_RES_0402LF-33       ,1%  ,1/A
BMC_CPLD_GPIO_21         R576             1        Q_RES_0402LF-0,5%,1/16W,CHIP,CA
BMC_CPLD_GPIO_21         R622             2        Q_RES_0402LF-4.7K,5%,1/16W,CHIA
BMC_CPLD_GPIO_21_R1      R480             2        Q_RES_0402LF-33       ,1%  ,1/A
BMC_CPLD_GPIO_21_R1      U5               Y25      AST2600A1GP-AST2600A1-GP,SMLF,A
BMC_CPLD_GPIO_21_R2      R576             2        Q_RES_0402LF-0,5%,1/16W,CHIP,CA
BMC_CPLD_GPIO_21_R2      U25              E12      10M02SCU169C8G-10M02SCU169C8G,A
BMC_CPLD_GPIO_3          R458             1        Q_RES_0402LF-33       ,1%  ,1/A
BMC_CPLD_GPIO_3          R520             1        Q_RES_0402LF-0,5%,1/16W,CHIP,CA
BMC_CPLD_GPIO_3          R587             2        Q_RES_0402LF-4.7K,5%,1/16W,CHIA
BMC_CPLD_GPIO_22         R489             1        Q_RES_0402LF-33       ,1%  ,1/A
BMC_CPLD_GPIO_22         R577             1        Q_RES_0402LF-0,5%,1/16W,CHIP,CA
BMC_CPLD_GPIO_22         R626             2        Q_RES_0402LF-4.7K,5%,1/16W,CHIA
BMC_CPLD_GPIO_22_R1      R489             2        Q_RES_0402LF-33       ,1%  ,1/A
BMC_CPLD_GPIO_22_R1      U5               AA26     AST2600A1GP-AST2600A1-GP,SMLF,A
BMC_CPLD_GPIO_22_R2      R577             2        Q_RES_0402LF-0,5%,1/16W,CHIP,CA
BMC_CPLD_GPIO_22_R2      U25              F9       10M02SCU169C8G-10M02SCU169C8G,A
BMC_CPLD_GPIO_23         R491             1        Q_RES_0402LF-33       ,1%  ,1/A
BMC_CPLD_GPIO_23         R578             1        Q_RES_0402LF-0,5%,1/16W,CHIP,CA
BMC_CPLD_GPIO_23         R627             2        Q_RES_0402LF-4.7K,5%,1/16W,CHIA
BMC_CPLD_GPIO_23_R1      R491             2        Q_RES_0402LF-33       ,1%  ,1/A
BMC_CPLD_GPIO_23_R1      U5               AD22     AST2600A1GP-AST2600A1-GP,SMLF,A
BMC_CPLD_GPIO_23_R2      R578             2        Q_RES_0402LF-0,5%,1/16W,CHIP,CA
BMC_CPLD_GPIO_23_R2      U25              D13      10M02SCU169C8G-10M02SCU169C8G,A
BMC_CPLD_GPIO_24         R493             1        Q_RES_0402LF-33       ,1%  ,1/A
BMC_CPLD_GPIO_24         R579             1        Q_RES_0402LF-0,5%,1/16W,CHIP,CA
BMC_CPLD_GPIO_24         R632             2        Q_RES_0402LF-4.7K,5%,1/16W,CHIA
BMC_CPLD_GPIO_24_R1      R493             2        Q_RES_0402LF-33       ,1%  ,1/A
BMC_CPLD_GPIO_24_R1      U5               AC22     AST2600A1GP-AST2600A1-GP,SMLF,A
BMC_CPLD_GPIO_24_R2      R579             2        Q_RES_0402LF-0,5%,1/16W,CHIP,CA
BMC_CPLD_GPIO_24_R2      U25              F10      10M02SCU169C8G-10M02SCU169C8G,A
BMC_CPLD_GPIO_25         R96              2        Q_RES_0402LF-33       ,1%  ,1/A
BMC_CPLD_GPIO_25         R634             1        Q_RES_0402LF-0,5%,1/16W,CHIP,CA
BMC_CPLD_GPIO_25         R640             2        Q_RES_0402LF-4.7K,5%,1/16W,CHIA
BMC_CPLD_GPIO_25_R1      R96              1        Q_RES_0402LF-33       ,1%  ,1/A
BMC_CPLD_GPIO_25_R1      U5               AA12     AST2600A1GP-AST2600A1-GP,SMLF,A
BMC_CPLD_GPIO_25_R2      R634             2        Q_RES_0402LF-0,5%,1/16W,CHIP,CA
BMC_CPLD_GPIO_25_R2      U25              C13      10M02SCU169C8G-10M02SCU169C8G,A
BMC_CPLD_GPIO_2_R1       R65              2        Q_RES_0402LF-33       ,1%  ,1/A
BMC_CPLD_GPIO_2_R1       U5               A23      AST2600A1GP-AST2600A1-GP,SMLF,A
BMC_CPLD_GPIO_2_R2       R519             2        Q_RES_0402LF-0,5%,1/16W,CHIP,CA
BMC_CPLD_GPIO_2_R2       U25              G5       10M02SCU169C8G-10M02SCU169C8G,A
BMC_CPLD_GPIO_3_R1       R458             2        Q_RES_0402LF-33       ,1%  ,1/A
BMC_CPLD_GPIO_3_R1       U5               E20      AST2600A1GP-AST2600A1-GP,SMLF,A
BMC_CPLD_GPIO_3_R2       R520             2        Q_RES_0402LF-0,5%,1/16W,CHIP,CA
BMC_CPLD_GPIO_3_R2       U25              L3       10M02SCU169C8G-10M02SCU169C8G,A
BMC_CPLD_GPIO_4          R459             1        Q_RES_0402LF-33       ,1%  ,1/A
BMC_CPLD_GPIO_4          R522             2        Q_RES_0402LF-33       ,1%  ,1/A
BMC_CPLD_GPIO_4          R588             2        Q_RES_0402LF-4.7K,5%,1/16W,CHIA
BMC_CPLD_GPIO_4_R1       R459             2        Q_RES_0402LF-33       ,1%  ,1/A
BMC_CPLD_GPIO_4_R1       U5               AD13     AST2600A1GP-AST2600A1-GP,SMLF,A
BMC_CPLD_GPIO_4_R2       R522             1        Q_RES_0402LF-33       ,1%  ,1/A
BMC_CPLD_GPIO_4_R2       U25              L4       10M02SCU169C8G-10M02SCU169C8G,A
BMC_CPLD_GPIO_5          R460             1        Q_RES_0402LF-33       ,1%  ,1/A
BMC_CPLD_GPIO_5          R524             2        Q_RES_0402LF-33       ,1%  ,1/A
BMC_CPLD_GPIO_5          R591             2        Q_RES_0402LF-4.7K,5%,1/16W,CHIA
BMC_CPLD_GPIO_5_R1       R460             2        Q_RES_0402LF-33       ,1%  ,1/A
BMC_CPLD_GPIO_5_R1       U5               AC10     AST2600A1GP-AST2600A1-GP,SMLF,A
BMC_CPLD_GPIO_5_R2       R524             1        Q_RES_0402LF-33       ,1%  ,1/A
BMC_CPLD_GPIO_5_R2       U25              M5       10M02SCU169C8G-10M02SCU169C8G,A
BMC_CPLD_GPIO_6          R461             1        Q_RES_0402LF-33       ,1%  ,1/A
BMC_CPLD_GPIO_6          R525             2        Q_RES_0402LF-33       ,1%  ,1/A
BMC_CPLD_GPIO_6          R592             2        Q_RES_0402LF-4.7K,5%,1/16W,CHIA
BMC_CPLD_GPIO_6_R1       R461             2        Q_RES_0402LF-33       ,1%  ,1/A
BMC_CPLD_GPIO_6_R1       U5               AD14     AST2600A1GP-AST2600A1-GP,SMLF,A
BMC_CPLD_GPIO_6_R2       R525             1        Q_RES_0402LF-33       ,1%  ,1/A
BMC_CPLD_GPIO_6_R2       U25              K5       10M02SCU169C8G-10M02SCU169C8G,A
BMC_CPLD_GPIO_7          R468             2        Q_RES_0402LF-33       ,1%  ,1/A
BMC_CPLD_GPIO_7          R526             2        Q_RES_0402LF-33       ,1%  ,1/A
BMC_CPLD_GPIO_7          R593             2        Q_RES_0402LF-4.7K,5%,1/16W,CHIA
BMC_CPLD_GPIO_7_R1       R468             1        Q_RES_0402LF-33       ,1%  ,1/A
BMC_CPLD_GPIO_7_R1       U5               AB11     AST2600A1GP-AST2600A1-GP,SMLF,A
BMC_CPLD_GPIO_7_R2       R526             1        Q_RES_0402LF-33       ,1%  ,1/A
BMC_CPLD_GPIO_7_R2       U25              M11      10M02SCU169C8G-10M02SCU169C8G,A
BMC_CPLD_GPIO_8          R469             2        Q_RES_0402LF-33       ,1%  ,1/A
BMC_CPLD_GPIO_8          R531             2        Q_RES_0402LF-33       ,1%  ,1/A
BMC_CPLD_GPIO_8          R595             2        Q_RES_0402LF-4.7K,5%,1/16W,CHIA
BMC_CPLD_GPIO_8_R1       R469             1        Q_RES_0402LF-33       ,1%  ,1/A
BMC_CPLD_GPIO_8_R1       U5               AA11     AST2600A1GP-AST2600A1-GP,SMLF,A
BMC_CPLD_GPIO_8_R2       R531             1        Q_RES_0402LF-33       ,1%  ,1/A
BMC_CPLD_GPIO_8_R2       U25              L11      10M02SCU169C8G-10M02SCU169C8G,A
BMC_CPLD_GPIO_9          R472             2        Q_RES_0402LF-33       ,1%  ,1/A
BMC_CPLD_GPIO_9          R533             2        Q_RES_0402LF-33       ,1%  ,1/A
BMC_CPLD_GPIO_9          R596             2        Q_RES_0402LF-4.7K,5%,1/16W,CHIA
BMC_CPLD_GPIO_9_R1       R472             1        Q_RES_0402LF-33       ,1%  ,1/A
BMC_CPLD_GPIO_9_R1       U5               AD11     AST2600A1GP-AST2600A1-GP,SMLF,A
BMC_CPLD_GPIO_9_R2       R533             1        Q_RES_0402LF-33       ,1%  ,1/A
BMC_CPLD_GPIO_9_R2       U25              J8       10M02SCU169C8G-10M02SCU169C8G,A
BMC_DDC_BUF_EN           R30              2        Q_RES_0402LF-0,5%,1/16W,CHIP,CA
BMC_DDC_BUF_EN           U26              1        74HC1G126GW-74HC1G126GW,SMLF,IA
BMC_DDC_BUF_EN           U33              1        74HC1G126GW-74HC1G126GW,SMLF,IA
BMC_DDC_BUF_PWR          R18              2        Q_RES_0402LF-0,5%,1/16W,CHIP,CA
BMC_DDC_BUF_PWR          U26              5        74HC1G126GW-74HC1G126GW,SMLF,IA
BMC_DDC_BUF_PWR          U33              5        74HC1G126GW-74HC1G126GW,SMLF,IA
BMC_EMMC_CD_N            R685             1        Q_RES_0402LF-1K,1%,1/16W,EMPTYA
BMC_EMMC_CD_N            R687             2        Q_RES_0402LF-4.7K,5%,1/16W,EMPA
BMC_EMMC_CD_N            U5               AC5      AST2600A1GP-AST2600A1-GP,SMLF,A
BMC_EMMC_CLK             R654             1        Q_RES_0402LF-33       ,1%  ,1/B
BMC_EMMC_CLK             U5               AB4      AST2600A1GP-AST2600A1-GP,SMLF,A
BMC_EMMC_CMD             R48              1        Q_RES_0402LF-33       ,1%  ,1/B
BMC_EMMC_CMD             U5               AA4      AST2600A1GP-AST2600A1-GP,SMLF,A
BMC_EMMC_DT0             R532             1        Q_RES_0402LF-33       ,1%  ,1/B
BMC_EMMC_DT0             U5               AC4      AST2600A1GP-AST2600A1-GP,SMLF,A
BMC_EMMC_DT1             R647             1        Q_RES_0402LF-33       ,1%  ,1/B
BMC_EMMC_DT1             U5               AA5      AST2600A1GP-AST2600A1-GP,SMLF,A
BMC_EMMC_DT2             R648             1        Q_RES_0402LF-33       ,1%  ,1/B
BMC_EMMC_DT2             U5               Y5       AST2600A1GP-AST2600A1-GP,SMLF,A
BMC_EMMC_DT3             R649             1        Q_RES_0402LF-33       ,1%  ,1/B
BMC_EMMC_DT3             U5               AB5      AST2600A1GP-AST2600A1-GP,SMLF,A
BMC_EMMC_DT4             R650             1        Q_RES_0402LF-33       ,1%  ,1/B
BMC_EMMC_DT4             U5               Y1       AST2600A1GP-AST2600A1-GP,SMLF,A
BMC_EMMC_DT5             R651             1        Q_RES_0402LF-33       ,1%  ,1/B
BMC_EMMC_DT5             U5               Y2       AST2600A1GP-AST2600A1-GP,SMLF,A
BMC_EMMC_DT6             R652             1        Q_RES_0402LF-33       ,1%  ,1/B
BMC_EMMC_DT6             U5               Y3       AST2600A1GP-AST2600A1-GP,SMLF,A
BMC_EMMC_DT7             R653             1        Q_RES_0402LF-33       ,1%  ,1/B
BMC_EMMC_DT7             U5               Y4       AST2600A1GP-AST2600A1-GP,SMLF,A
BMC_EMMC_RST_N           C230             1        Q_CAP_C0402-1UF,25V,10%,EMPTY,A
BMC_EMMC_RST_N           R164             2        Q_RES_0402LF-10K,1%,1/16W,EMPTA
BMC_EMMC_RST_N           U20              K5       MTFC8GAKAJCN1MWT-MTFC8GAKAJCN-A
BMC_EMMC_WP_N            R684             1        Q_RES_0402LF-1K,1%,1/16W,EMPTYA
BMC_EMMC_WP_N            R686             2        Q_RES_0402LF-4.7K,5%,1/16W,EMPA
BMC_EMMC_WP_N            U5               AB6      AST2600A1GP-AST2600A1-GP,SMLF,A
BMC_HEARTBEAT_N          D8               C        Q_LED_SMLF-LED_GREEN,19-213/GVA
BMC_HEARTBEAT_N          U5               Y23      AST2600A1GP-AST2600A1-GP,SMLF,A
BMC_HEARTBEAT_R_N        D8               A        Q_LED_SMLF-LED_GREEN,19-213/GVA
BMC_HEARTBEAT_R_N        R167             2        Q_RES_0402LF-330,1%,1/16W,CHIPA
BMC_PWR_LED              R316             1        Q_RES_0402LF-0,5%,1/16W,CHIP,CA
BMC_PWR_LED              U5               W23      AST2600A1GP-AST2600A1-GP,SMLF,A
CLK_25M_OSC_FPGA         R807             2        Q_RES_0402LF-33       ,1%  ,1/A
CLK_25M_OSC_FPGA         U25              H6       10M02SCU169C8G-10M02SCU169C8G,A
CLK_25M_OSC_FPGA_R       OSC2             3        OSC4_7X25000018-25MHZ,SMLF,MISA
CLK_25M_OSC_FPGA_R       R807             1        Q_RES_0402LF-33       ,1%  ,1/A
CLK_BMC_GF_DN            GF1              A13      FCONN168_ME1016810106011-FCONNA
CLK_BMC_GF_DN            U5               AD6      AST2600A1GP-AST2600A1-GP,SMLF,A
CLK_BMC_GF_DP            GF1              A12      FCONN168_ME1016810106011-FCONNA
CLK_BMC_GF_DP            U5               AD5      AST2600A1GP-AST2600A1-GP,SMLF,A
CRT_VCC5                 C204             1        Q_CAP_0603-1UF,16V,10%,EMPTY,TA
CRT_VCC5                 D9               C        SCHOTTKY_AC-SS0530,SMLF,EMPTY,A
CRT_VCC5                 D11              C        SCHOTTKY_AC-SS0530,SMLF,IC,BCSA
CRT_VCC5                 D12              1        BZA462A-BZA462A,SMLF,IC,BCZA46A
CRT_VCC5                 D12              3        BZA462A-BZA462A,SMLF,IC,BCZA46A
CRT_VCC5                 D12              4        BZA462A-BZA462A,SMLF,IC,BCZA46A
CRT_VCC5                 D12              6        BZA462A-BZA462A,SMLF,IC,BCZA46A
CRT_VCC5                 D16              A        SCHOTTKY_AC-RB161SS-20T2R,SMLFA
CRT_VCC5                 R16              2        Q_RES_0402LF-2.21K    ,1%  ,1/A
CRT_VCC5                 R17              2        Q_RES_0402LF-2.21K    ,1%  ,1/A
CRT_VCC5                 R27              2        Q_RES_0603-0,5%,1/10W,EMPTY,TMA
CRT_VCC5                 R30              1        Q_RES_0402LF-0,5%,1/16W,CHIP,CA
CRT_VCC5                 R91              1        Q_RES_0402LF-2.2K ,5%,1/16W,CHA
CRT_VCC5                 R92              1        Q_RES_0402LF-2.2K ,5%,1/16W,CHA
CRT_VCC5                 U34              5        TPD4E001DBVR-TPD4E001DBVR,SMLFA
CRT_VCC5                 U35              5        TPD4E001DBVR-TPD4E001DBVR,SMLFA
DEBUG_PORT_PRSNT         J2               7        CONN9_GSB311131HR-CONN9_GSB311A
DEBUG_PORT_PRSNT         R205             1        Q_RES_0402LF-20K,1%,1/16W,CHIPA
DEBUG_PORT_PRSNT         U23              2        SN74LVC1G07DBVR_SMLF-SN74LVC1GA
DEBUG_PORT_PRSNT         U29              1        74HC1G126GW-74HC1G126GW,SMLF,IA
DEBUG_PORT_PRSNT         U36              1        74HC1G126GW-74HC1G126GW,SMLF,IA
DEBUG_PORT_PRSNT_BUF_EN  D13              5        PCA9517ADP_SMLF-PCA9517ADP,IC,A
DEBUG_PORT_PRSNT_BUF_EN  R295             2        Q_RES_0402LF-10K,1%,1/16W,EMPTA
DEBUG_PORT_PRSNT_BUF_EN  R296             1        Q_RES_0402LF-100K,1%,1/16W,EMPB
DEBUG_PORT_PRSNT_BUF_EN  U23              4        SN74LVC1G07DBVR_SMLF-SN74LVC1GA
DEBUG_PORT_UART_RX       J2               9        CONN9_GSB311131HR-CONN9_GSB311A
DEBUG_PORT_UART_RX       R274             2        Q_RES_0402LF-100K,1%,1/16W,EMPB
DEBUG_PORT_UART_RX       U36              2        74HC1G126GW-74HC1G126GW,SMLF,IA
DEBUG_PORT_UART_TX       J2               8        CONN9_GSB311131HR-CONN9_GSB311A
DEBUG_PORT_UART_TX       R219             1        Q_RES_0402LF-100K,1%,1/16W,EMPB
DEBUG_PORT_UART_TX       U29              4        74HC1G126GW-74HC1G126GW,SMLF,IA
DP_BMC_AUX_C_N           C186             1        Q_CAP_0402-0.1UF,25V,10%,X7R,CA
DP_BMC_AUX_C_N           D10              1        BZA462A-BZA462A,SMLF,IC,BCZA46A
DP_BMC_AUX_C_N           J3               18       SCONN20_3VM11207D7307H-SCONN20A
DP_BMC_AUX_C_N           R10              2        Q_RES_0402LF-10K,1%,1/16W,CHIPA
DP_BMC_AUX_C_P           C185             1        Q_CAP_0402-0.1UF,25V,10%,X7R,CA
DP_BMC_AUX_C_P           D10              4        BZA462A-BZA462A,SMLF,IC,BCZA46A
DP_BMC_AUX_C_P           J3               16       SCONN20_3VM11207D7307H-SCONN20A
DP_BMC_AUX_C_P           R392             1        Q_RES_0402LF-100K,1%,1/16W,CHIA
DP_BMC_AUX_N             C186             2        Q_CAP_0402-0.1UF,25V,10%,X7R,CA
DP_BMC_AUX_N             U5               AB3      AST2600A1GP-AST2600A1-GP,SMLF,A
DP_BMC_AUX_P             C185             2        Q_CAP_0402-0.1UF,25V,10%,X7R,CA
DP_BMC_AUX_P             U5               AC3      AST2600A1GP-AST2600A1-GP,SMLF,A
DP_BMC_C_TX0_N           C27              1        Q_CAP_0402-0.1UF,25V,10%,X7R,CA
DP_BMC_C_TX0_N           U5               AB1      AST2600A1GP-AST2600A1-GP,SMLF,A
DP_BMC_C_TX0_P           C26              1        Q_CAP_0402-0.1UF,25V,10%,X7R,CA
DP_BMC_C_TX0_P           U5               AC1      AST2600A1GP-AST2600A1-GP,SMLF,A
DP_BMC_C_TX1_N           C29              1        Q_CAP_0402-0.1UF,25V,10%,X7R,CA
DP_BMC_C_TX1_N           U5               AA2      AST2600A1GP-AST2600A1-GP,SMLF,A
DP_BMC_C_TX1_P           C28              1        Q_CAP_0402-0.1UF,25V,10%,X7R,CA
DP_BMC_C_TX1_P           U5               AB2      AST2600A1GP-AST2600A1-GP,SMLF,A
DP_BMC_HPD_3V3           D10              3        BZA462A-BZA462A,SMLF,IC,BCZA46A
DP_BMC_HPD_3V3           J3               2        SCONN20_3VM11207D7307H-SCONN20A
DP_BMC_HPD_3V3           R391             1        Q_RES_0402LF-100K,1%,1/16W,CHIA
DP_BMC_HPD_3V3           U5               C7       AST2600A1GP-AST2600A1-GP,SMLF,A
DP_BMC_TX0_N             C27              2        Q_CAP_0402-0.1UF,25V,10%,X7R,CA
DP_BMC_TX0_N             J3               5        SCONN20_3VM11207D7307H-SCONN20A
DP_BMC_TX0_N             U16              4        TPD4E001DBVR-TPD4E001DBVR,SMLFA
DP_BMC_TX0_P             C26              2        Q_CAP_0402-0.1UF,25V,10%,X7R,CA
DP_BMC_TX0_P             J3               3        SCONN20_3VM11207D7307H-SCONN20A
DP_BMC_TX0_P             U16              6        TPD4E001DBVR-TPD4E001DBVR,SMLFA
DP_BMC_TX1_N             C29              2        Q_CAP_0402-0.1UF,25V,10%,X7R,CA
DP_BMC_TX1_N             J3               11       SCONN20_3VM11207D7307H-SCONN20A
DP_BMC_TX1_N             U16              3        TPD4E001DBVR-TPD4E001DBVR,SMLFA
DP_BMC_TX1_P             C28              2        Q_CAP_0402-0.1UF,25V,10%,X7R,CA
DP_BMC_TX1_P             J3               9        SCONN20_3VM11207D7307H-SCONN20A
DP_BMC_TX1_P             U16              1        TPD4E001DBVR-TPD4E001DBVR,SMLFA
DP_CONFIG1               J3               4        SCONN20_3VM11207D7307H-SCONN20A
DP_CONFIG1               R395             1        Q_RES_0402LF-1M,1%,1/16W,CHIP,A
DP_CONFIG2               J3               6        SCONN20_3VM11207D7307H-SCONN20A
DP_CONFIG2               R396             1        Q_RES_0402LF-1M,1%,1/16W,CHIP,A
EMMC_CLK_R               R654             2        Q_RES_0402LF-33       ,1%  ,1/B
EMMC_CLK_R               U20              M6       MTFC8GAKAJCN1MWT-MTFC8GAKAJCN-A
EMMC_CMD_R               R48              2        Q_RES_0402LF-33       ,1%  ,1/B
EMMC_CMD_R               R663             2        Q_RES_0402LF-10K,1%,1/16W,EMPTA
EMMC_CMD_R               U20              M5       MTFC8GAKAJCN1MWT-MTFC8GAKAJCN-A
EMMC_DT0_R               R532             2        Q_RES_0402LF-33       ,1%  ,1/B
EMMC_DT0_R               R655             2        Q_RES_0402LF-10K,1%,1/16W,EMPTA
EMMC_DT0_R               U20              A3       MTFC8GAKAJCN1MWT-MTFC8GAKAJCN-A
EMMC_DT1_R               R647             2        Q_RES_0402LF-33       ,1%  ,1/B
EMMC_DT1_R               R656             2        Q_RES_0402LF-10K,1%,1/16W,EMPTA
EMMC_DT1_R               U20              A4       MTFC8GAKAJCN1MWT-MTFC8GAKAJCN-A
EMMC_DT2_R               R648             2        Q_RES_0402LF-33       ,1%  ,1/B
EMMC_DT2_R               R657             2        Q_RES_0402LF-10K,1%,1/16W,EMPTA
EMMC_DT2_R               U20              A5       MTFC8GAKAJCN1MWT-MTFC8GAKAJCN-A
EMMC_DT3_R               R649             2        Q_RES_0402LF-33       ,1%  ,1/B
EMMC_DT3_R               R658             2        Q_RES_0402LF-10K,1%,1/16W,EMPTA
EMMC_DT3_R               U20              B2       MTFC8GAKAJCN1MWT-MTFC8GAKAJCN-A
EMMC_DT4_R               R650             2        Q_RES_0402LF-33       ,1%  ,1/B
EMMC_DT4_R               R659             2        Q_RES_0402LF-10K,1%,1/16W,EMPTA
EMMC_DT4_R               U20              B3       MTFC8GAKAJCN1MWT-MTFC8GAKAJCN-A
EMMC_DT5_R               R651             2        Q_RES_0402LF-33       ,1%  ,1/B
EMMC_DT5_R               R660             2        Q_RES_0402LF-10K,1%,1/16W,EMPTA
EMMC_DT5_R               U20              B4       MTFC8GAKAJCN1MWT-MTFC8GAKAJCN-A
EMMC_DT6_R               R652             2        Q_RES_0402LF-33       ,1%  ,1/B
EMMC_DT6_R               R661             2        Q_RES_0402LF-10K,1%,1/16W,EMPTA
EMMC_DT6_R               U20              B5       MTFC8GAKAJCN1MWT-MTFC8GAKAJCN-A
EMMC_DT7_R               R653             2        Q_RES_0402LF-33       ,1%  ,1/B
EMMC_DT7_R               R662             2        Q_RES_0402LF-10K,1%,1/16W,EMPTA
EMMC_DT7_R               U20              B6       MTFC8GAKAJCN1MWT-MTFC8GAKAJCN-A
EN_P1V2_AUX              PU41             5        NB695GDZ-NB695GD-Z,SMLF,IC,AL0A
EN_P1V2_AUX              R708             2        Q_RES_0402LF-0,5%,1/16W,CHIP,CA
EN_P1V2_AUX              R764             2        Q_RES_0402LF-0,5%,1/16W,EMPTY,A
EN_P5V_AUX               PC205            1        Q_CAP_0402-0.1UF,25V,10%,X7R,CA
EN_P5V_AUX               PR521            2        Q_RES_0402LF-681K,1%,1/16W,CHIA
EN_P5V_AUX               PR522            1        Q_RES_0402LF-100K,1%,1/16W,CHIA
EN_P5V_AUX               PU38             8        MPQ8633AGLEC807Z-MPQ8633AGLE-CA
ESPI_HOST_LPC_BMC_CLK    GF1              B1       FCONN168_ME1016810106011-FCONNA
ESPI_HOST_LPC_BMC_CLK    U5               AE7      AST2600A1GP-AST2600A1-GP,SMLF,A
ESPI_HOST_LPC_BMC_LFRAME_N GF1              B2       FCONN168_ME1016810106011-FCONNA
ESPI_HOST_LPC_BMC_LFRAME_N R115             2        Q_RES_0402LF-4.7K,5%,1/16W,CHIA
ESPI_HOST_LPC_BMC_LFRAME_N U5               AF7      AST2600A1GP-AST2600A1-GP,SMLF,A
ESPI_LPC_D0_IO0          R128             1        Q_RES_0402LF-33       ,1%  ,1/A
ESPI_LPC_D0_IO0          U5               AB7      AST2600A1GP-AST2600A1-GP,SMLF,A
ESPI_LPC_D1_IO1          R129             1        Q_RES_0402LF-33       ,1%  ,1/A
ESPI_LPC_D1_IO1          U5               AB8      AST2600A1GP-AST2600A1-GP,SMLF,A
ESPI_LPC_D2_IO2          R130             1        Q_RES_0402LF-33       ,1%  ,1/A
ESPI_LPC_D2_IO2          U5               AC8      AST2600A1GP-AST2600A1-GP,SMLF,A
ESPI_LPC_D3_IO3          R131             1        Q_RES_0402LF-33       ,1%  ,1/A
ESPI_LPC_D3_IO3          U5               AC7      AST2600A1GP-AST2600A1-GP,SMLF,A
ESPI_LPC_LAD0_IO0        GF1              B5       FCONN168_ME1016810106011-FCONNA
ESPI_LPC_LAD0_IO0        R128             2        Q_RES_0402LF-33       ,1%  ,1/A
ESPI_LPC_LAD1_IO1        GF1              B6       FCONN168_ME1016810106011-FCONNA
ESPI_LPC_LAD1_IO1        R129             2        Q_RES_0402LF-33       ,1%  ,1/A
ESPI_LPC_LAD2_IO2        GF1              B7       FCONN168_ME1016810106011-FCONNA
ESPI_LPC_LAD2_IO2        R130             2        Q_RES_0402LF-33       ,1%  ,1/A
ESPI_LPC_LAD3_IO3        GF1              B8       FCONN168_ME1016810106011-FCONNA
ESPI_LPC_LAD3_IO3        R131             2        Q_RES_0402LF-33       ,1%  ,1/A
FM_ADR_COMPLETE          U5               AC24     AST2600A1GP-AST2600A1-GP,SMLF,A
FM_ADR_COMPLETE          U25              J6       10M02SCU169C8G-10M02SCU169C8G,A
FM_ADR_TRIGGER_N         U5               AD25     AST2600A1GP-AST2600A1-GP,SMLF,A
FM_ADR_TRIGGER_N         U25              H13      10M02SCU169C8G-10M02SCU169C8G,A
FM_BIOS_DEBUG_EN_N       R112             2        Q_RES_0402LF-33       ,1%  ,1/A
FM_BIOS_DEBUG_EN_N       U25              A6       10M02SCU169C8G-10M02SCU169C8G,A
FM_BIOS_DEBUG_EN_R_N     R56              2        Q_RES_0402LF-4.7K,5%,1/16W,CHIA
FM_BIOS_DEBUG_EN_R_N     R112             1        Q_RES_0402LF-33       ,1%  ,1/A
FM_BIOS_DEBUG_EN_R_N     U5               AE11     AST2600A1GP-AST2600A1-GP,SMLF,A
FM_BIOS_POST_CMPLT_BMC_N U5               U26      AST2600A1GP-AST2600A1-GP,SMLF,A
FM_BIOS_POST_CMPLT_BMC_N U25              H5       10M02SCU169C8G-10M02SCU169C8G,A
FM_BMC_BIOS_MUX_CS_SPI_R_SEL_0 R852             2        Q_RES_0402LF-33       ,1%  ,1/A
FM_BMC_BIOS_MUX_CS_SPI_R_SEL_0 R866             1        Q_RES_0402LF-10K,1%,1/16W,CHIPA
FM_BMC_BIOS_MUX_CS_SPI_R_SEL_0 U21              1        IDTQS3VH257PAG_SMLF-IDTQS3VH25A
FM_BMC_BIOS_MUX_CS_SPI_R_SEL_0 U30              1        IDTQS3VH257PAG_SMLF-IDTQS3VH25A
FM_BMC_CPU_FBRK_OUT_N    R242             2        Q_RES_0402LF-33       ,1%  ,1/A
FM_BMC_CPU_FBRK_OUT_N    U5               D23      AST2600A1GP-AST2600A1-GP,SMLF,A
FM_BMC_CPU_FBRK_OUT_R_N  GF1              A55      FCONN168_ME1016810106011-FCONNA
FM_BMC_CPU_FBRK_OUT_R_N  R242             1        Q_RES_0402LF-33       ,1%  ,1/A
FM_BMC_DBP_PRESENT_N     R705             1        Q_RES_0402LF-33       ,1%  ,1/A
FM_BMC_DBP_PRESENT_N     R706             2        Q_RES_0402LF-4.7K,5%,1/16W,CHIA
FM_BMC_DBP_PRESENT_N     U25              F4       10M02SCU169C8G-10M02SCU169C8G,A
FM_BMC_DBP_PRESENT_R_N   R705             2        Q_RES_0402LF-33       ,1%  ,1/A
FM_BMC_DBP_PRESENT_R_N   U5               B21      AST2600A1GP-AST2600A1-GP,SMLF,A
FM_BMC_DEBUG_SW_N        R11              2        Q_RES_0402LF-4.7K,1%,1/16W,CHIA
FM_BMC_DEBUG_SW_N        R624             2        Q_RES_0402LF-4.7K,5%,1/16W,CHIA
FM_BMC_DEBUG_SW_N        SW3              3        SW4S_DHNF02FTVTR-SW4S_DHNF-02FA
FM_BMC_DEBUG_SW_N        U2               6        SN74LVC1G3157DCKR-SN74LVC1G315A
FM_BMC_DEBUG_SW_N        U3               6        SN74LVC1G3157DCKR-SN74LVC1G315A
FM_BMC_DEBUG_SW_N        U5               R26      AST2600A1GP-AST2600A1-GP,SMLF,A
FM_BMC_DISABLE           SW1              3        SW4S_DHNF02FTVTR-SW4S_DHNF-02FA
FM_BMC_DISABLE           U11              3        BAT54C-BAT54C,SMLF,IC,BCBAT54CA
FM_BMC_EN_DET_R          R846             2        Q_RES_0402LF-4.7K,5%,1/16W,EMPA
FM_BMC_EN_DET_R          U5               AA16     AST2600A1GP-AST2600A1-GP,SMLF,A
FM_BMC_EN_DET_R          U25              G13      10M02SCU169C8G-10M02SCU169C8G,A
FM_BMC_MUX_CS_SPI_SEL_0  R852             1        Q_RES_0402LF-33       ,1%  ,1/A
FM_BMC_MUX_CS_SPI_SEL_0  U5               J23      AST2600A1GP-AST2600A1-GP,SMLF,A
FM_BMC_ONCTL_R_N         R430             2        Q_RES_0402LF-4.7K,5%,1/16W,CHIA
FM_BMC_ONCTL_R_N         R821             2        Q_RES_0402LF-4.7K,5%,1/16W,EMPA
FM_BMC_ONCTL_R_N         U5               AC15     AST2600A1GP-AST2600A1-GP,SMLF,A
FM_BMC_ONCTL_R_N         U11              1        BAT54C-BAT54C,SMLF,IC,BCBAT54CA
FM_BMC_ONCTL_R_N         U25              G12      10M02SCU169C8G-10M02SCU169C8G,A
FM_BMC_READY_PLD_N       R111             2        Q_RES_0402LF-33       ,1%  ,1/A
FM_BMC_READY_PLD_N       U25              A7       10M02SCU169C8G-10M02SCU169C8G,A
FM_BMC_READY_R_PLD_N     R55              2        Q_RES_0402LF-4.7K,5%,1/16W,CHIA
FM_BMC_READY_R_PLD_N     R111             1        Q_RES_0402LF-33       ,1%  ,1/A
FM_BMC_READY_R_PLD_N     U5               AE14     AST2600A1GP-AST2600A1-GP,SMLF,A
FM_BMC_SSPRST_N          R211             2        Q_RES_0402LF-10K,1%,1/16W,CHIPA
FM_BMC_SSPRST_N          U5               D7       AST2600A1GP-AST2600A1-GP,SMLF,A
FM_BMC_SUSACK_N          R38              2        Q_RES_0402LF-4.7K,5%,1/16W,EMPA
FM_BMC_SUSACK_N          U5               AD15     AST2600A1GP-AST2600A1-GP,SMLF,A
FM_CPU_MSMI_CATERR_LVT3_N R121             1        Q_RES_0402LF-33       ,1%  ,1/A
FM_CPU_MSMI_CATERR_LVT3_N R163             2        Q_RES_0402LF-4.7K,5%,1/16W,CHIA
FM_CPU_MSMI_CATERR_LVT3_N R270             1        Q_RES_0402LF-33       ,1%  ,1/A
FM_CPU_MSMI_CATERR_LVT3_PLD_N R270             2        Q_RES_0402LF-33       ,1%  ,1/A
FM_CPU_MSMI_CATERR_LVT3_PLD_N U25              J5       10M02SCU169C8G-10M02SCU169C8G,A
FM_CPU_RMCA_CATERR_LVT3_R_N R121             2        Q_RES_0402LF-33       ,1%  ,1/A
FM_CPU_RMCA_CATERR_LVT3_R_N U5               E22      AST2600A1GP-AST2600A1-GP,SMLF,A
FM_DBP_BMC_PRDY_N        GF1              A50      FCONN168_ME1016810106011-FCONNA
FM_DBP_BMC_PRDY_N        R237             1        Q_RES_0402LF-33       ,1%  ,1/A
FM_DBP_BMC_PRDY_R_N      R237             2        Q_RES_0402LF-33       ,1%  ,1/A
FM_DBP_BMC_PRDY_R_N      U5               C12      AST2600A1GP-AST2600A1-GP,SMLF,A
FM_DBP_CPU_PREQ_GF_N     R158             2        Q_RES_0402LF-33       ,1%  ,1/A
FM_DBP_CPU_PREQ_GF_N     U5               C15      AST2600A1GP-AST2600A1-GP,SMLF,A
FM_DBP_CPU_PREQ_GF_R_N   GF1              A49      FCONN168_ME1016810106011-FCONNA
FM_DBP_CPU_PREQ_GF_R_N   R158             1        Q_RES_0402LF-33       ,1%  ,1/A
FM_ESPI_PLD_EN           R444             1        Q_RES_0402LF-33       ,1%  ,1/A
FM_ESPI_PLD_EN           R833             1        Q_RES_0402LF-33       ,1%  ,1/A
FM_ESPI_PLD_R1_EN        R444             2        Q_RES_0402LF-33       ,1%  ,1/A
FM_ESPI_PLD_R1_EN        U5               H25      AST2600A1GP-AST2600A1-GP,SMLF,A
FM_ESPI_PLD_R_EN         R833             2        Q_RES_0402LF-33       ,1%  ,1/A
FM_ESPI_PLD_R_EN         U25              J12      10M02SCU169C8G-10M02SCU169C8G,A
FM_ID_LED_N              Q12              4        MOSFET_DUAL_6P-2N7002KDW,SMLF,A
FM_ID_LED_N              R502             2        Q_RES_0402LF-4.7K,1%,1/16W,CHIA
FM_ID_LED_N              U5               G26      AST2600A1GP-AST2600A1-GP,SMLF,A
FM_INTRUDER_HDR_PCH_N    GF1              A54      FCONN168_ME1016810106011-FCONNA
FM_INTRUDER_HDR_PCH_N    R440             2        Q_RES_0402LF-33       ,1%  ,1/A
FM_INTRUDER_HDR_PCH_R_N  R440             1        Q_RES_0402LF-33       ,1%  ,1/A
FM_INTRUDER_HDR_PCH_R_N  R441             2        Q_RES_0402LF-4.7K,5%,1/16W,CHIA
FM_INTRUDER_HDR_PCH_R_N  U5               R24      AST2600A1GP-AST2600A1-GP,SMLF,A
FM_JTAG_TCK_MUX_BMC_SEL  R159             1        Q_RES_0402LF-33       ,1%  ,1/A
FM_JTAG_TCK_MUX_BMC_SEL  R616             2        Q_RES_0402LF-0,5%,1/16W,EMPTY,A
FM_JTAG_TCK_MUX_BMC_SEL  R620             1        Q_RES_0402LF-100K,1%,1/16W,CHIA
FM_JTAG_TCK_MUX_BMC_SEL  U25              E4       10M02SCU169C8G-10M02SCU169C8G,A
FM_JTAG_TCK_MUX_BMC_SEL_R R616             1        Q_RES_0402LF-0,5%,1/16W,EMPTY,A
FM_JTAG_TCK_MUX_BMC_SEL_R SW1              4        SW4S_DHNF02FTVTR-SW4S_DHNF-02FA
FM_JTAG_TCK_MUX_BMC_SEL_R1 R159             2        Q_RES_0402LF-33       ,1%  ,1/A
FM_JTAG_TCK_MUX_BMC_SEL_R1 U5               F15      AST2600A1GP-AST2600A1-GP,SMLF,A
FM_MASTER_MB_N           R845             2        Q_RES_0402LF-4.7K,5%,1/16W,EMPA
FM_MASTER_MB_N           U5               AC16     AST2600A1GP-AST2600A1-GP,SMLF,A
FM_MASTER_MB_N           U25              H9       10M02SCU169C8G-10M02SCU169C8G,A
FM_MB_STBY_EN            GF1              A45      FCONN168_ME1016810106011-FCONNA
FM_MB_STBY_EN            R105             2        Q_RES_0402LF-10K,1%,1/16W,EMPTA
FM_MB_STBY_EN            R114             1        Q_RES_0402LF-33       ,1%  ,1/A
FM_MB_STBY_EN            R618             2        Q_RES_0402LF-10K,1%,1/16W,CHIPA
FM_MB_STBY_R_EN          R114             2        Q_RES_0402LF-33       ,1%  ,1/A
FM_MB_STBY_R_EN          U25              L5       10M02SCU169C8G-10M02SCU169C8G,A
FM_ME_BT_DONE            R266             2        Q_RES_0402LF-4.7K,5%,1/16W,EMPA
FM_ME_BT_DONE            U5               J26      AST2600A1GP-AST2600A1-GP,SMLF,A
FM_ME_BT_DONE            U25              J1       10M02SCU169C8G-10M02SCU169C8G,A
FM_PCHHOT_R_N            U5               AD16     AST2600A1GP-AST2600A1-GP,SMLF,A
FM_PCHHOT_R_N            U25              H8       10M02SCU169C8G-10M02SCU169C8G,A
FM_PCH_BMC_THERMTRIP_N   R62              2        Q_RES_0402LF-4.7K,5%,1/16W,CHIA
FM_PCH_BMC_THERMTRIP_N   R763             1        Q_RES_0402LF-33       ,1%  ,1/A
FM_PCH_BMC_THERMTRIP_N   U25              H4       10M02SCU169C8G-10M02SCU169C8G,A
FM_PCIE_M2_SSD0_PRSNT_N  U5               AD23     AST2600A1GP-AST2600A1-GP,SMLF,A
FM_PCIE_M2_SSD0_PRSNT_N  U25              J2       10M02SCU169C8G-10M02SCU169C8G,A
FM_PECI_SEL_N            R439             1        Q_RES_0402LF-33       ,1%  ,1/A
FM_PECI_SEL_N            R446             2        Q_RES_0402LF-4.7K,5%,1/16W,CHIA
FM_PECI_SEL_N            U25              L1       10M02SCU169C8G-10M02SCU169C8G,A
FM_PECI_SEL_R_N          R439             2        Q_RES_0402LF-33       ,1%  ,1/A
FM_PECI_SEL_R_N          U5               E14      AST2600A1GP-AST2600A1-GP,SMLF,A
FM_PLT_BMC_THERMTRIP_N_R R763             2        Q_RES_0402LF-33       ,1%  ,1/A
FM_PLT_BMC_THERMTRIP_N_R U5               A21      AST2600A1GP-AST2600A1-GP,SMLF,A
FM_PMBUS_ALERT_EN        U5               AD26     AST2600A1GP-AST2600A1-GP,SMLF,A
FM_PMBUS_ALERT_EN        U25              J9       10M02SCU169C8G-10M02SCU169C8G,A
FM_PRSNT_0_R_N           GF1              OB3      FCONN168_ME1016810106011-FCONNA
FM_PRSNT_0_R_N           R822             2        Q_RES_0402LF-0,5%,1/16W,CHIP,CA
FM_PRSNT_1_N             GF1              A57      FCONN168_ME1016810106011-FCONNA
FM_PRSNT_1_N             R822             1        Q_RES_0402LF-0,5%,1/16W,CHIP,CA
FM_PWR_BTN               R225             1        Q_RES_0402LF-33       ,1%  ,1/A
FM_PWR_BTN               R432             2        Q_RES_0402LF-0,5%,1/16W,EMPTY,A
FM_PWR_BTN               U5               AB22     AST2600A1GP-AST2600A1-GP,SMLF,A
FM_PWR_R_BTN             R432             1        Q_RES_0402LF-0,5%,1/16W,EMPTY,A
FM_PWR_R_BTN             U25              A10      10M02SCU169C8G-10M02SCU169C8G,A
FM_RISER1_JTAG_SEL_N     R404             2        Q_RES_0402LF-33       ,1%  ,1/A
FM_RISER1_JTAG_SEL_N     U25              B6       10M02SCU169C8G-10M02SCU169C8G,A
FM_RISER1_JTAG_SEL_R_N   R57              2        Q_RES_0402LF-4.7K,5%,1/16W,CHIA
FM_RISER1_JTAG_SEL_R_N   R404             1        Q_RES_0402LF-33       ,1%  ,1/A
FM_RISER1_JTAG_SEL_R_N   U5               P23      AST2600A1GP-AST2600A1-GP,SMLF,A
FM_RISER2_JTAG_SEL_N     R90              2        Q_RES_0402LF-33       ,1%  ,1/A
FM_RISER2_JTAG_SEL_N     U25              A4       10M02SCU169C8G-10M02SCU169C8G,A
FM_RISER2_JTAG_SEL_R_N   R58              2        Q_RES_0402LF-4.7K,5%,1/16W,CHIA
FM_RISER2_JTAG_SEL_R_N   R90              1        Q_RES_0402LF-33       ,1%  ,1/A
FM_RISER2_JTAG_SEL_R_N   U5               T24      AST2600A1GP-AST2600A1-GP,SMLF,A
FM_SLPS3_GF_N            R773             1        Q_RES_0402LF-33       ,1%  ,1/A
FM_SLPS3_GF_N            R774             2        Q_RES_0402LF-4.7K,5%,1/16W,CHIA
FM_SLPS3_GF_N            U5               AB15     AST2600A1GP-AST2600A1-GP,SMLF,A
FM_SLPS3_GF_R_N          R773             2        Q_RES_0402LF-33       ,1%  ,1/A
FM_SLPS3_GF_R_N          U25              K12      10M02SCU169C8G-10M02SCU169C8G,A
FM_SPD_REMOTE_EN_R       U5               AC23     AST2600A1GP-AST2600A1-GP,SMLF,A
FM_SPD_REMOTE_EN_R       U25              M13      10M02SCU169C8G-10M02SCU169C8G,A
FM_THERMTRIP_DLY_LVC1_R_N U5               T26      AST2600A1GP-AST2600A1-GP,SMLF,A
FM_THERMTRIP_DLY_LVC1_R_N U25              K7       10M02SCU169C8G-10M02SCU169C8G,A
FM_THROTTLE_N            R45              2        Q_RES_0402LF-4.7K,5%,1/16W,CHIA
FM_THROTTLE_N            R769             1        Q_RES_0402LF-33       ,1%  ,1/A
FM_THROTTLE_N            U5               B16      AST2600A1GP-AST2600A1-GP,SMLF,A
FM_THROTTLE_R_N          R769             2        Q_RES_0402LF-33       ,1%  ,1/A
FM_THROTTLE_R_N          U25              K13      10M02SCU169C8G-10M02SCU169C8G,A
FM_TPM_PRSNT_0_N         J5               8        SCONN11_9192031111LF-SCONN11_9A
FM_TPM_PRSNT_0_N         R464             2        Q_RES_0402LF-10K,1%,1/16W,CHIPA
FM_TPM_PRSNT_0_N         R767             1        Q_RES_0402LF-33       ,1%  ,1/A
FM_TPM_PRSNT_0_R_N       R767             2        Q_RES_0402LF-33       ,1%  ,1/A
FM_TPM_PRSNT_0_R_N       U25              D1       10M02SCU169C8G-10M02SCU169C8G,A
FM_TPM_PRSNT_1_N         J10              8        SCONN11_9192031111LF-SCONN11_9A
FM_TPM_PRSNT_1_N         R50              2        Q_RES_0402LF-10K,1%,1/16W,CHIPA
FM_TPM_PRSNT_1_N         R123             1        Q_RES_0402LF-33       ,1%  ,1/A
FM_TPM_PRSNT_1_R_N       R123             2        Q_RES_0402LF-33       ,1%  ,1/A
FM_TPM_PRSNT_1_R_N       U25              C1       10M02SCU169C8G-10M02SCU169C8G,A
FM_VIRTUAL_RESEAT        GF1              OA14     FCONN168_ME1016810106011-FCONNA
FM_VIRTUAL_RESEAT        R823             2        Q_RES_0402LF-100K,1%,1/16W,CHIA
FM_VIRTUAL_RESEAT        R824             1        Q_RES_0402LF-33       ,1%  ,1/A
FM_VIRTUAL_RESEAT_BMC    R824             2        Q_RES_0402LF-33       ,1%  ,1/A
FM_VIRTUAL_RESEAT_BMC    U5               B13      AST2600A1GP-AST2600A1-GP,SMLF,A
FRU_E0                   R12              2        Q_RES_0402LF-4.7K,5%,1/16W,CHIA
FRU_E0                   R411             1        Q_RES_0402LF-100,1%,1/16W,EMPTA
FRU_E0                   U19              1        M24128BWDW6TP-M24128-BWDW6TP,SA
FRU_E1                   R13              2        Q_RES_0402LF-4.7K,5%,1/16W,EMPA
FRU_E1                   R412             1        Q_RES_0402LF-100,1%,1/16W,CHIPA
FRU_E1                   U19              2        M24128BWDW6TP-M24128-BWDW6TP,SA
FRU_E2                   R14              2        Q_RES_0402LF-4.7K,5%,1/16W,EMPA
FRU_E2                   R413             1        Q_RES_0402LF-100,1%,1/16W,CHIPA
FRU_E2                   U19              3        M24128BWDW6TP-M24128-BWDW6TP,SA
GND                      C1               2        Q_CAP_C0603-4.7UF,25V,10%,X6S,A
GND                      C2               2        Q_CAP_C0402-1UF,25V,10%,X6S,CHA
GND                      C3               2        Q_CAP_C0402-1UF,25V,10%,X6S,CHA
GND                      C4               2        Q_CAP_C0402-1UF,25V,10%,X6S,CHA
GND                      C5               2        Q_CAP_C0402-1UF,25V,10%,X6S,CHA
GND                      C6               2        Q_CAP_0402-0.1UF,25V,10%,X7R,CA
GND                      C7               2        Q_CAP_0402-0.1UF,25V,10%,X7R,CA
GND                      C8               2        Q_CAP_0402-0.1UF,25V,10%,X7R,CA
GND                      C9               2        Q_CAP_0402-100PF,50V,5%,NPO,CHA
GND                      C10              2        Q_CAP_0402-0.1UF,25V,10%,X7R,CA
GND                      C11              2        Q_CAP_0402-0.1UF,10V,10%,EMPTYA
GND                      C12              2        Q_CAP_0402-0.22UF,16V,10%,X7R,A
GND                      C13              2        Q_CAP_0402-0.1UF,25V,10%,X7R,CA
GND                      C14              2        Q_CAP_0402-0.1UF,25V,10%,X7R,CA
GND                      C15              2        Q_CAP_C0402-10UF,6.3V,20%,X6S,A
GND                      C16              2        Q_CAP_C0402-10UF,6.3V,20%,X6S,A
GND                      C17              2        Q_CAP_0402-0.1UF,25V,10%,X7R,CA
GND                      C18              2        Q_CAP_0402-0.1UF,25V,10%,X7R,CA
GND                      C19              2        Q_CAP_0402-0.1UF,25V,10%,X7R,CA
GND                      C20              2        Q_CAP_0402-0.1UF,25V,10%,X7R,CA
GND                      C21              2        Q_CAP_C0402-0.01UF,50V,10%,EMPA
GND                      C22              2        Q_CAP_0402-0.1UF,25V,10%,EMPTYA
GND                      C23              2        Q_CAP_0402-0.1UF,25V,10%,X7R,CA
GND                      C30              2        Q_CAP_C0402-1UF,25V,10%,X6S,CHA
GND                      C31              2        Q_CAP_0402-0.1UF,25V,10%,X7R,CA
GND                      C32              2        Q_CAP_C0402-1UF,25V,10%,X6S,CHA
GND                      C33              2        Q_CAP_0402-0.1UF,25V,10%,X7R,CA
GND                      C34              2        Q_CAP_0402-0.1UF,25V,10%,X7R,CA
GND                      C35              2        Q_CAP_C0402-1UF,25V,10%,X6S,CHA
GND                      C36              2        Q_CAP_0402-0.1UF,25V,10%,X7R,CA
GND                      C37              2        Q_CAP_0402-0.1UF,25V,10%,X7R,CA
GND                      C38              2        Q_CAP_C0402-1UF,25V,10%,X6S,CHA
GND                      C39              2        Q_CAP_0402-0.1UF,25V,10%,X7R,CA
GND                      C40              2        Q_CAP_C0402-4.7UF,10V,10%,X5R,A
GND                      C41              2        Q_CAP_0402-0.1UF,25V,10%,X7R,CA
GND                      C42              2        Q_CAP_C0603-22UF,6.3V,20%,X6S,A
GND                      C43              2        Q_CAP_C0402-1UF,25V,10%,X6S,CHA
GND                      C44              2        Q_CAP_C0402-4.7UF,10V,10%,X5R,A
GND                      C45              2        Q_CAP_0402-0.1UF,25V,10%,X7R,CA
GND                      C46              2        Q_CAP_C0402-1UF,25V,10%,X6S,CHA
GND                      C47              2        Q_CAP_C0402-1UF,25V,10%,X6S,CHA
GND                      C48              2        Q_CAP_C0402-1UF,25V,10%,X6S,CHA
GND                      C49              2        Q_CAP_0402-0.1UF,25V,10%,X7R,CA
GND                      C50              2        Q_CAP_0402-0.1UF,25V,10%,X7R,CA
GND                      C51              2        Q_CAP_0402-0.1UF,25V,10%,X7R,CA
GND                      C52              2        Q_CAP_C0402-1UF,25V,10%,X6S,CHA
GND                      C53              2        Q_CAP_C0402-1UF,25V,10%,X6S,CHA
GND                      C54              2        Q_CAP_0402-0.1UF,25V,10%,X7R,CA
GND                      C55              2        Q_CAP_C0603-22UF,6.3V,20%,X6S,A
GND                      C56              2        Q_CAP_C0402-1UF,25V,10%,X6S,CHA
GND                      C57              2        Q_CAP_0402-0.1UF,25V,10%,X7R,CA
GND                      C58              2        Q_CAP_C0402-1UF,25V,10%,X6S,CHA
GND                      C59              2        Q_CAP_0402-0.1UF,25V,10%,X7R,CA
GND                      C60              2        Q_CAP_C0402-1UF,25V,10%,X6S,CHA
GND                      C61              2        Q_CAP_C0402-1UF,25V,10%,X6S,CHA
GND                      C62              2        Q_CAP_C0402-1UF,25V,10%,X6S,CHA
GND                      C63              2        Q_CAP_0402-2200PF,50V,10%,X7R,A
GND                      C64              2        Q_CAP_C0402-1UF,25V,10%,X6S,CHA
GND                      C65              2        Q_CAP_0402-0.1UF,25V,10%,X7R,CA
GND                      C66              2        Q_CAP_0402-0.1UF,25V,10%,X7R,CA
GND                      C67              2        Q_CAP_C0402-1UF,25V,10%,X6S,CHA
GND                      C68              2        Q_CAP_0402-0.1UF,25V,10%,X7R,CA
GND                      C69              2        Q_CAP_0402-0.1UF,25V,10%,X7R,CA
GND                      C70              2        Q_CAP_0402-0.1UF,25V,10%,X7R,CA
GND                      C71              2        Q_CAP_0402-0.1UF,25V,10%,X7R,CA
GND                      C72              2        Q_CAP_0402-0.1UF,25V,10%,X7R,CA
GND                      C73              2        Q_CAP_0402-0.1UF,25V,10%,X7R,CA
GND                      C74              2        Q_CAP_0402-0.1UF,25V,10%,X7R,CA
GND                      C75              2        Q_CAP_C0402-1UF,25V,10%,X6S,CHA
GND                      C76              2        Q_CAP_0402-0.1UF,25V,10%,X7R,CA
GND                      C77              2        Q_CAP_0402-0.1UF,25V,10%,X7R,CA
GND                      C78              2        Q_CAP_C0402-1UF,25V,10%,X6S,CHA
GND                      C79              2        Q_CAP_0402-0.1UF,25V,10%,X7R,CA
GND                      C80              2        Q_CAP_C0402-1UF,25V,10%,X6S,CHA
GND                      C81              2        Q_CAP_0402-0.1UF,25V,10%,X7R,CA
GND                      C82              2        Q_CAP_0402-0.1UF,25V,10%,X7R,CA
GND                      C83              2        Q_CAP_0402-0.1UF,25V,10%,X7R,CA
GND                      C84              2        Q_CAP_0402-0.1UF,25V,10%,X7R,CA
GND                      C85              2        Q_CAP_0402-0.1UF,25V,10%,X7R,CA
GND                      C86              2        Q_CAP_0402-0.1UF,25V,10%,X7R,CA
GND                      C87              2        Q_CAP_0402-0.1UF,25V,10%,X7R,CA
GND                      C88              2        Q_CAP_0402-0.1UF,25V,10%,X7R,CA
GND                      C89              2        Q_CAP_0402-0.1UF,25V,10%,X7R,CA
GND                      C90              2        Q_CAP_C0402-1UF,25V,10%,X6S,CHA
GND                      C91              2        Q_CAP_0402-0.1UF,25V,10%,X7R,CA
GND                      C92              2        Q_CAP_0402-0.1UF,25V,10%,X7R,CA
GND                      C93              2        Q_CAP_0402-0.1UF,25V,10%,X7R,CA
GND                      C94              2        Q_CAP_0402-0.1UF,25V,10%,X7R,CA
GND                      C95              2        Q_CAP_0402-0.1UF,25V,10%,X7R,CA
GND                      C96              2        Q_CAP_0402-0.1UF,25V,10%,X7R,CA
GND                      C97              2        Q_CAP_0402-0.1UF,25V,10%,X7R,CA
GND                      C98              2        Q_CAP_0402-0.1UF,25V,10%,X7R,CA
GND                      C99              2        Q_CAP_0402-0.1UF,25V,10%,X7R,CA
GND                      C100             2        Q_CAP_0402-0.1UF,25V,10%,X7R,CA
GND                      C101             2        Q_CAP_0402-0.1UF,25V,10%,X7R,CA
GND                      C102             2        Q_CAP_0402-0.1UF,25V,10%,X7R,CA
GND                      C103             2        Q_CAP_0402-0.1UF,25V,10%,X7R,CA
GND                      C104             2        Q_CAP_C0402-1UF,25V,10%,X6S,CHA
GND                      C105             2        Q_CAP_0402-0.1UF,25V,10%,X7R,CA
GND                      C106             2        Q_CAP_C0402-1UF,25V,10%,X6S,CHA
GND                      C107             2        Q_CAP_0402-0.1UF,25V,10%,X7R,CA
GND                      C108             2        Q_CAP_C0402-1UF,25V,10%,X6S,CHA
GND                      C109             2        Q_CAP_0402-0.1UF,25V,10%,X7R,CA
GND                      C110             2        Q_CAP_C0402-1UF,25V,10%,X6S,CHA
GND                      C111             2        Q_CAP_C0402-1UF,25V,10%,X6S,CHA
GND                      C112             2        Q_CAP_0402-0.1UF,25V,10%,X7R,CA
GND                      C113             2        Q_CAP_C0603-22UF,10V,20%,X5R,CA
GND                      C114             2        Q_CAP_C0402-1UF,25V,10%,X6S,CHA
GND                      C115             2        Q_CAP_C0402-1UF,25V,10%,X6S,CHA
GND                      C116             2        Q_CAP_C0402-1UF,25V,10%,X6S,CHA
GND                      C117             2        Q_CAP_C0402-1UF,25V,10%,X6S,CHA
GND                      C118             2        Q_CAP_C0603-22UF,6.3V,20%,X6S,A
GND                      C119             2        Q_CAP_C0402-1UF,25V,10%,X6S,CHA
GND                      C120             2        Q_CAP_C0603-22UF,10V,20%,X5R,CA
GND                      C121             2        Q_CAP_C0603-22UF,6.3V,20%,X6S,A
GND                      C122             2        Q_CAP_C0402-1UF,25V,10%,X6S,CHA
GND                      C123             2        Q_CAP_C0603-22UF,6.3V,20%,X6S,A
GND                      C124             2        Q_CAP_C0603-22UF,6.3V,20%,X6S,A
GND                      C125             2        Q_CAP_C0603-22UF,10V,20%,X5R,CA
GND                      C126             2        Q_CAP_C0603-22UF,6.3V,20%,X6S,A
GND                      C127             2        Q_CAP_C0402-1UF,25V,10%,X6S,CHA
GND                      C128             2        Q_CAP_C0402-1UF,25V,10%,X6S,CHA
GND                      C129             2        Q_CAP_C0402-1UF,25V,10%,X6S,CHA
GND                      C130             2        Q_CAP_0402-0.1UF,25V,10%,X7R,CA
GND                      C131             2        Q_CAP_C0603-22UF,10V,20%,X5R,CA
GND                      C132             2        Q_CAP_C0603-22UF,10V,20%,X5R,CA
GND                      C133             1        Q_CAP_C0402-0.01UF,50V,10%,X7RA
GND                      C134             1        Q_CAP_C0402-0.01UF,50V,10%,X7RA
GND                      C135             1        Q_CAP_C0402-0.01UF,50V,10%,X7RA
GND                      C136             1        Q_CAP_C0402-0.01UF,50V,10%,X7RA
GND                      C139             2        Q_CAP_0402-0.1UF,25V,10%,X7R,CA
GND                      C140             2        Q_CAP_0402-0.1UF,25V,10%,X7R,CA
GND                      C141             2        Q_CAP_C0402-12PF,50V,5%,C0G,CHA
GND                      C142             1        Q_CAP_C0402-0.01UF,50V,10%,EMPA
GND                      C143             2        Q_CAP_C0402-10UF,10V,20%,X5R,CA
GND                      C144             2        Q_CAP_0402-0.1UF,25V,10%,X7R,CA
GND                      C145             2        Q_CAP_C0402-12PF,50V,5%,C0G,CHA
GND                      C146             2        Q_CAP_0402-0.1UF,25V,10%,X7R,CA
GND                      C147             2        Q_CAP_0402-0.1UF,25V,10%,X7R,CA
GND                      C148             2        Q_CAP_0402-0.1UF,25V,10%,X7R,CA
GND                      C149             2        Q_CAP_0402-0.1UF,25V,10%,X7R,CA
GND                      C150             2        Q_CAP_C0402-0.001UF,50V,10%,X7A
GND                      C151             2        Q_CAP_C0402-0.001UF,50V,10%,X7A
GND                      C152             2        Q_CAP_0402-22PF,50V,5%,EMPTY,TA
GND                      C153             2        Q_CAP_C0402-0.001UF,50V,10%,X7A
GND                      C154             2        Q_CAP_C0402-0.001UF,50V,10%,X7A
GND                      C155             2        Q_CAP_C0402-0.001UF,50V,10%,X7A
GND                      C156             2        Q_CAP_C0402-0.001UF,50V,10%,X7A
GND                      C157             2        Q_CAP_0402-0.1UF,25V,10%,X7R,CA
GND                      C158             2        Q_CAP_0402-0.1UF,25V,10%,X7R,CA
GND                      C159             2        Q_CAP_0402-0.1UF,25V,10%,X7R,CA
GND                      C160             2        Q_CAP_0402-0.1UF,25V,10%,X7R,CA
GND                      C162             2        Q_CAP_C0603-10UF,16V,20%,X6S,CA
GND                      C163             2        Q_CAP_C0402-0.01UF,50V,10%,X7RA
GND                      C164             2        Q_CAP_C0402-0.01UF,50V,10%,X7RA
GND                      C165             2        Q_CAP_0402-100PF,50V,5%,NPO,CHA
GND                      C166             2        Q_CAP_0402-100PF,50V,5%,NPO,CHA
GND                      C167             2        Q_CAP_0402-100PF,50V,5%,NPO,CHA
GND                      C168             2        Q_CAP_0402-0.1UF,25V,10%,X7R,CA
GND                      C170             2        Q_CAP_C0402-0.01UF,50V,10%,X7RA
GND                      C171             2        Q_CAP_C0805-22UF,16V,20%,X6S,CA
GND                      C172             2        Q_CAP_0402-470PF,50V,10%,X7R,TA
GND                      C173             2        Q_CAP_C0402-0.1UF,25V,10%,X6S,A
GND                      C174             2        Q_CAP_0402-0.1UF,25V,10%,X7R,CA
GND                      C175             2        Q_CAP_0402-0.1UF,25V,10%,X7R,CA
GND                      C177             2        Q_CAP_1206-47UF ,10V,20%,X5R,CA
GND                      C178             2        Q_CAP_0402-470PF,50V,10%,X7R,TA
GND                      C179             2        Q_CAP_0402-470PF,50V,10%,X7R,TA
GND                      C180             2        Q_CAP_C0402-0.1UF,16V,10%,X7R,A
GND                      C181             2        Q_CAP_0402-1UF,16V,10%,EMPTY,TA
GND                      C182             2        Q_CAP_C0402-0.1UF,16V,10%,X7R,A
GND                      C183             2        Q_CAP_C0603-22UF,10V,20%,X5R,CA
GND                      C184             2        Q_CAP_C0603-22UF,10V,20%,X5R,CA
GND                      C187             2        Q_CAP_0402-0.1UF,25V,10%,X7R,CA
GND                      C188             2        Q_CAP_C0603-10UF,16V,20%,X6S,CA
GND                      C189             2        Q_CAP_0402-0.1UF,25V,10%,X7R,CA
GND                      C190             2        Q_CAP_C0603-10UF,16V,20%,X6S,CA
GND                      C191             2        Q_CAP_0402-0.1UF,25V,10%,X7R,CA
GND                      C192             2        Q_CAP_0402-0.1UF,25V,10%,X7R,CA
GND                      C193             2        Q_CAP_0402-2.2UF,10V,20%,X5R,TA
GND                      C194             2        Q_CAP_0402-0.1UF,25V,10%,X7R,CA
GND                      C195             2        Q_CAP_0402-0.1UF,25V,10%,X7R,CA
GND                      C196             2        Q_CAP_0402-0.1UF,25V,10%,X7R,CA
GND                      C197             2        Q_CAP_0402-0.1UF,25V,10%,X7R,CA
GND                      C198             2        Q_CAP_C0402-1UF,25V,10%,X6S,CHA
GND                      C199             2        Q_CAP_C0402-1UF,25V,10%,X6S,CHA
GND                      C200             2        Q_CAP_0402-0.1UF,25V,10%,X7R,CA
GND                      C201             2        Q_CAP_0402-0.1UF,25V,10%,X7R,CA
GND                      C202             2        Q_CAP_0402-0.1UF,25V,10%,X7R,CA
GND                      C203             2        Q_CAP_0402-0.1UF,25V,10%,X7R,CA
GND                      C204             2        Q_CAP_0603-1UF,16V,10%,EMPTY,TA
GND                      C205             2        Q_CAP_0402-10PF,50V,1%,NPO,TMPA
GND                      C206             2        Q_CAP_0402-10PF,50V,1%,NPO,TMPA
GND                      C207             2        Q_CAP_0402-10PF,50V,1%,NPO,TMPA
GND                      C208             2        Q_CAP_C0402-33PF,50V,1%,C0G,CHA
GND                      C209             2        Q_CAP_C0402-33PF,50V,1%,C0G,CHA
GND                      C210             2        Q_CAP_C0402-33PF,50V,1%,C0G,CHA
GND                      C211             2        Q_CAP_0402-10PF,50V,5%,COG,CH0A
GND                      C212             2        Q_CAP_0402-10PF,50V,5%,COG,CH0A
GND                      C213             2        Q_CAP_0402-100PF,50V,5%,EMPTY,A
GND                      C214             2        Q_CAP_0402-100PF,50V,5%,EMPTY,A
GND                      C215             2        Q_CAP_C0402-10UF,10V,20%,X5R,CA
GND                      C217             2        Q_CAP_0402-0.1UF,25V,10%,X7R,CA
GND                      C220             2        Q_CAP_0402-0.1UF,25V,10%,X7R,CA
GND                      C221             2        Q_CAP_0402-0.1UF,25V,10%,X7R,CA
GND                      C222             2        Q_CAP_0402-0.1UF,25V,10%,X7R,CA
GND                      C223             2        Q_CAP_C0402-4700P,25V,10%,EMPTA
GND                      C224             2        Q_CAP_C0402-10UF,10V,20%,X5R,CA
GND                      C225             2        Q_CAP_0402-0.1UF,25V,10%,X7R,CA
GND                      C226             2        Q_CAP_0402-0.1UF,10V,10%,EMPTYA
GND                      C227             2        Q_CAP_0402-0.1UF,10V,10%,EMPTYA
GND                      C228             2        Q_CAP_0402-0.1UF,10V,10%,EMPTYA
GND                      C230             2        Q_CAP_C0402-1UF,25V,10%,EMPTY,A
GND                      C231             2        Q_CAP_C0402-1UF,6.3V,10%,EMPTYA
GND                      C232             2        Q_CAP_C0603-22UF,6.3V,20%,EMPTA
GND                      C233             2        Q_CAP_0402-0.1UF,10V,10%,EMPTYA
GND                      C234             2        Q_CAP_C0603-22UF,10V,20%,EMPTYA
GND                      C235             2        Q_CAP_0402-0.1UF,10V,10%,EMPTYA
GND                      C240             2        Q_CAP_C0402-0.1UF,16V,10%,X7R,A
GND                      C241             2        Q_CAP_0402-0.1UF,10V,10%,X7R,TA
GND                      C244             2        Q_CAP_C0402-1UF,25V,10%,X6S,CHA
GND                      C246             2        Q_CAP_C0402-0.01UF,50V,10%,X7RA
GND                      C248             2        Q_CAP_C0402-10UF,10V,20%,X5R,CA
GND                      C249             2        Q_CAP_0402-0.1UF,25V,10%,X7R,CA
GND                      C251             2        Q_CAP_C0402-0.1UF,16V,10%,X7R,A
GND                      C252             2        Q_CAP_C0402-0.1UF,16V,10%,EMPTA
GND                      C253             2        Q_CAP_0402-0.1UF,25V,10%,X7R,CA
GND                      C255             2        Q_CAP_0402-0.1UF,25V,10%,X7R,CA
GND                      C256             2        Q_CAP_C0402-1UF,25V,10%,X6S,CHA
GND                      C257             2        Q_CAP_C0402-1UF,25V,10%,X6S,CHA
GND                      C258             2        Q_CAP_C0402-0.01UF,50V,10%,X7RA
GND                      C259             2        Q_CAP_C0402-0.01UF,50V,10%,X7RA
GND                      C262             2        Q_CAP_C0402-10UF,6.3V,20%,X6S,A
GND                      C263             2        Q_CAP_0402-0.1UF,25V,10%,X7R,CA
GND                      C264             2        Q_CAP_0402-0.1UF,25V,10%,X7R,CA
GND                      C265             2        Q_CAP_0402-0.1UF,10V,10%,X7R,TA
GND                      C266             2        Q_CAP_0402-0.1UF,25V,10%,X7R,CA
GND                      C267             2        Q_CAP_0402-1UF,16V,10%,EMPTY,TA
GND                      C268             2        Q_CAP_0402-1UF,16V,10%,EMPTY,TA
GND                      C269             2        Q_CAP_0402-0.1UF,25V,10%,X7R,CA
GND                      C270             2        Q_CAP_0402-1UF,16V,10%,EMPTY,TA
GND                      C272             2        Q_CAP_0402-2.2UF,10V,20%,X5R,TA
GND                      C273             2        Q_CAP_0402-1UF,16V,10%,EMPTY,TA
GND                      C274             2        Q_CAP_0402-0.1UF,25V,10%,X7R,CA
GND                      C275             2        Q_CAP_0402-100PF,50V,5%,NPO,CHA
GND                      C277             2        Q_CAP_C0402-1UF,25V,10%,X6S,CHA
GND                      C278             2        Q_CAP_0402-0.1UF,25V,10%,X7R,CA
GND                      C279             2        Q_CAP_0402-0.1UF,25V,10%,X7R,CA
GND                      C281             2        Q_CAP_0402-0.1UF,25V,10%,X7R,CA
GND                      C282             2        Q_CAP_C0402-1UF,25V,10%,X6S,CHA
GND                      C284             2        Q_CAP_0402-0.1UF,25V,10%,X7R,CA
GND                      C287             2        Q_CAP_0402-0.1UF,25V,10%,X7R,CA
GND                      C288             2        Q_CAP_0402-0.1UF,10V,10%,X7R,TA
GND                      C289             2        Q_CAP_0402-0.1UF,25V,10%,X7R,CA
GND                      C290             2        Q_CAP_0402-0.1UF,25V,10%,X7R,CA
GND                      C293             2        Q_CAP_0402-0.1UF,10V,10%,X7R,TA
GND                      C295             2        Q_CAP_0402-0.1UF,25V,10%,X7R,CA
GND                      C297             2        Q_CAP_0402-0.1UF,10V,10%,X7R,TA
GND                      C298             2        Q_CAP_0402-0.1UF,25V,10%,X7R,CA
GND                      C299             2        Q_CAP_0402-0.1UF,25V,10%,X7R,CA
GND                      C301             2        Q_CAP_0402-0.1UF,10V,10%,X7R,TA
GND                      C302             2        Q_CAP_0402-0.1UF,25V,10%,X7R,CA
GND                      C303             2        Q_CAP_0402-0.1UF,25V,10%,X7R,CA
GND                      C305             2        Q_CAP_0402-0.1UF,10V,10%,X7R,TA
GND                      C306             2        Q_CAP_0402-0.1UF,25V,10%,X7R,CA
GND                      C307             2        Q_CAP_0402-0.1UF,25V,10%,X7R,CA
GND                      C308             2        Q_CAP_0402-0.1UF,25V,10%,X7R,CA
GND                      C309             2        Q_CAP_0402-0.1UF,25V,10%,X7R,CA
GND                      C310             2        Q_CAP_0402-0.1UF,25V,10%,X7R,CA
GND                      C311             2        Q_CAP_0402-0.1UF,25V,10%,X7R,CA
GND                      C312             2        Q_CAP_0402-0.1UF,25V,10%,X7R,CA
GND                      C313             2        Q_CAP_0402-0.1UF,25V,10%,X7R,CA
GND                      C314             2        Q_CAP_0402-0.1UF,25V,10%,X7R,CA
GND                      C315             2        Q_CAP_0402-0.1UF,25V,10%,X7R,CA
GND                      C317             2        Q_CAP_0402-0.1UF,25V,10%,X7R,CA
GND                      C318             2        Q_CAP_0402-0.1UF,25V,10%,X7R,CA
GND                      C319             2        Q_CAP_0402-0.1UF,25V,10%,X7R,CA
GND                      C320             2        Q_CAP_0402-0.1UF,25V,10%,X7R,CA
GND                      C321             2        Q_CAP_0402-0.1UF,25V,10%,X7R,CA
GND                      C323             2        Q_CAP_0402-0.1UF,25V,10%,X7R,CA
GND                      C324             2        Q_CAP_0402-470PF,50V,10%,X7R,TA
GND                      C326             2        Q_CAP_0402-470PF,50V,10%,X7R,TA
GND                      C327             2        Q_CAP_1206-47UF ,10V,20%,X5R,CA
GND                      C328             2        Q_CAP_0402-0.1UF,10V,10%,X7R,TA
GND                      C329             2        Q_CAP_C0805-22UF,25V,20%,X5R,CA
GND                      C330             2        Q_CAP_C0805-22UF,25V,20%,X5R,CA
GND                      C331             2        Q_CAP_0402-0.1UF,10V,10%,X7R,TA
GND                      C332             2        Q_CAP_0402-0.1UF,10V,10%,X7R,TA
GND                      C333             2        Q_CAP_0402-0.1UF,10V,10%,X7R,TA
GND                      C334             2        Q_CAP_0402-0.1UF,10V,10%,X7R,TA
GND                      C339             2        Q_CAP_0402-0.1UF,25V,10%,X7R,CA
GND                      C340             2        Q_CAP_0402-0.1UF,25V,10%,X7R,CA
GND                      C341             2        Q_CAP_0402-0.1UF,25V,10%,X7R,CA
GND                      C342             2        Q_CAP_0402-0.1UF,25V,10%,X7R,CA
GND                      C343             2        Q_CAP_0402-0.1UF,25V,10%,X7R,CA
GND                      C344             2        Q_CAP_0402-0.1UF,25V,10%,X7R,CA
GND                      C345             2        Q_CAP_0402-0.1UF,25V,10%,X7R,CA
GND                      C346             2        Q_CAP_C0402-22UF,6.3V,20%,X5R,A
GND                      C347             2        Q_CAP_0402-4.7UF,10V,10%,X5R,CA
GND                      C348             2        Q_CAP_0402-4.7UF,10V,10%,X5R,CA
GND                      C349             2        Q_CAP_C0402-22UF,6.3V,20%,X5R,A
GND                      C350             2        Q_CAP_0402-4.7UF,10V,10%,X5R,CA
GND                      D10              2        BZA462A-BZA462A,SMLF,IC,BCZA46A
GND                      D10              5        BZA462A-BZA462A,SMLF,IC,BCZA46A
GND                      D12              2        BZA462A-BZA462A,SMLF,IC,BCZA46A
GND                      D12              5        BZA462A-BZA462A,SMLF,IC,BCZA46A
GND                      D13              4        PCA9517ADP_SMLF-PCA9517ADP,IC,A
GND                      GF1              A11      FCONN168_ME1016810106011-FCONNA
GND                      GF1              A14      FCONN168_ME1016810106011-FCONNA
GND                      GF1              A17      FCONN168_ME1016810106011-FCONNA
GND                      GF1              A20      FCONN168_ME1016810106011-FCONNA
GND                      GF1              A33      FCONN168_ME1016810106011-FCONNA
GND                      GF1              A42      FCONN168_ME1016810106011-FCONNA
GND                      GF1              A43      FCONN168_ME1016810106011-FCONNA
GND                      GF1              A58      FCONN168_ME1016810106011-FCONNA
GND                      GF1              A61      FCONN168_ME1016810106011-FCONNA
GND                      GF1              A64      FCONN168_ME1016810106011-FCONNA
GND                      GF1              A67      FCONN168_ME1016810106011-FCONNA
GND                      GF1              A70      FCONN168_ME1016810106011-FCONNA
GND                      GF1              B10      FCONN168_ME1016810106011-FCONNA
GND                      GF1              B17      FCONN168_ME1016810106011-FCONNA
GND                      GF1              B26      FCONN168_ME1016810106011-FCONNA
GND                      GF1              B33      FCONN168_ME1016810106011-FCONNA
GND                      GF1              B38      FCONN168_ME1016810106011-FCONNA
GND                      GF1              B43      FCONN168_ME1016810106011-FCONNA
GND                      GF1              B52      FCONN168_ME1016810106011-FCONNA
GND                      GF1              B55      FCONN168_ME1016810106011-FCONNA
GND                      GF1              B58      FCONN168_ME1016810106011-FCONNA
GND                      GF1              B61      FCONN168_ME1016810106011-FCONNA
GND                      GF1              B64      FCONN168_ME1016810106011-FCONNA
GND                      GF1              B67      FCONN168_ME1016810106011-FCONNA
GND                      GF1              B70      FCONN168_ME1016810106011-FCONNA
GND                      GF1              OA3      FCONN168_ME1016810106011-FCONNA
GND                      GF1              OA4      FCONN168_ME1016810106011-FCONNA
GND                      GF1              OA13     FCONN168_ME1016810106011-FCONNA
GND                      GF1              OB4      FCONN168_ME1016810106011-FCONNA
GND                      GF1              OB7      FCONN168_ME1016810106011-FCONNA
GND                      GF1              OB10     FCONN168_ME1016810106011-FCONNA
GND                      H1               1        HOLE_TH-EMPTY,HOLE620
GND                      H2               1        HOLE_TH-EMPTY,HOLE620
GND                      H5               1        HOLE_TH-EMPTY,HOLE1211
GND                      H6               1        HOLE_TH-EMPTY,HOLE1101
GND                      H7               1        HOLE_TH-EMPTY,HOLE1101
GND                      H9               1        HOLE_TH-EMPTY,HOLE1211
GND                      J1               G1       SCONN14_RS6QU0001-SCONN14_RS6-A
GND                      J1               G2       SCONN14_RS6QU0001-SCONN14_RS6-A
GND                      J2               4        CONN9_GSB311131HR-CONN9_GSB311A
GND                      J2               G1       CONN9_GSB311131HR-CONN9_GSB311A
GND                      J2               G2       CONN9_GSB311131HR-CONN9_GSB311A
GND                      J3               1        SCONN20_3VM11207D7307H-SCONN20A
GND                      J3               7        SCONN20_3VM11207D7307H-SCONN20A
GND                      J3               8        SCONN20_3VM11207D7307H-SCONN20A
GND                      J3               13       SCONN20_3VM11207D7307H-SCONN20A
GND                      J3               14       SCONN20_3VM11207D7307H-SCONN20A
GND                      J3               19       SCONN20_3VM11207D7307H-SCONN20A
GND                      J3               G1       SCONN20_3VM11207D7307H-SCONN20A
GND                      J3               G2       SCONN20_3VM11207D7307H-SCONN20A
GND                      J3               G3       SCONN20_3VM11207D7307H-SCONN20A
GND                      J3               G4       SCONN20_3VM11207D7307H-SCONN20A
GND                      J4               4        SCONN5_2UB2141000111F-SCONN5_2A
GND                      J4               5        SCONN5_2UB2141000111F-SCONN5_2A
GND                      J4               G1       SCONN5_2UB2141000111F-SCONN5_2A
GND                      J4               G2       SCONN5_2UB2141000111F-SCONN5_2A
GND                      J4               G3       SCONN5_2UB2141000111F-SCONN5_2A
GND                      J4               G4       SCONN5_2UB2141000111F-SCONN5_2A
GND                      J5               11       SCONN11_9192031111LF-SCONN11_9A
GND                      J5               G1       SCONN11_9192031111LF-SCONN11_9A
GND                      J5               G2       SCONN11_9192031111LF-SCONN11_9A
GND                      J6               2        CONN3_210P9103GBR1-CONN3_210-PA
GND                      J7               7        CONN7_4400547-CONN7_440054-7,TA
GND                      J8               2        SCONN13_502240130C001-SCONN13_A
GND                      J8               4        SCONN13_502240130C001-SCONN13_A
GND                      J8               6        SCONN13_502240130C001-SCONN13_A
GND                      J8               8        SCONN13_502240130C001-SCONN13_A
GND                      J8               10       SCONN13_502240130C001-SCONN13_A
GND                      J8               G1       SCONN13_502240130C001-SCONN13_A
GND                      J8               G2       SCONN13_502240130C001-SCONN13_A
GND                      J10              11       SCONN11_9192031111LF-SCONN11_9A
GND                      J10              G1       SCONN11_9192031111LF-SCONN11_9A
GND                      J10              G2       SCONN11_9192031111LF-SCONN11_9A
GND                      J40              10       SCONN16_ACASPI006P06-SCONN16_AA
GND                      J121             10       SCONN16_ACASPI006P06-SCONN16_AA
GND                      OSC1             2        OSC4_7X25000018-25MHZ,SMLF,MISA
GND                      OSC2             2        OSC4_7X25000018-25MHZ,SMLF,MISA
GND                      PC205            2        Q_CAP_0402-0.1UF,25V,10%,X7R,CA
GND                      PC206            2        Q_CAP_C0805-10UF,25V,10%,X6S,CA
GND                      PC207            2        Q_CAP_C0805-10UF,25V,10%,X6S,CA
GND                      PC208            2        Q_CAP_C0402-1UF,25V,10%,X6S,CHA
GND                      PC210            2        Q_CAP_0402-0.1UF,25V,10%,X7R,CA
GND                      PC212            2        Q_CAP_0402-0.1UF,25V,10%,X7R,CA
GND                      PC213            2        Q_CAP_C0805-22UF,16V,20%,X6S,CA
GND                      PC214            2        Q_CAP_C0805-22UF,16V,20%,X6S,CA
GND                      PC215            2        Q_CAP_C0805-22UF,16V,20%,X6S,CA
GND                      PC217            2        Q_CAP_C0805-22UF,16V,20%,X6S,CA
GND                      PC218            2        Q_CAP_C0805-10UF,25V,10%,X6S,CA
GND                      PC219            2        Q_CAP_C0805-10UF,25V,10%,X6S,CA
GND                      PC221            2        Q_CAP_C0402-1UF,25V,10%,X6S,CHA
GND                      PC223            2        Q_CAP_0402-0.1UF,25V,10%,X7R,CA
GND                      PC225            2        Q_CAP_0402-0.1UF,25V,10%,X7R,CA
GND                      PC226            2        Q_CAP_C0805-22UF,10V,20%,X6S,CA
GND                      PC227            2        Q_CAP_C0805-22UF,10V,20%,X6S,CA
GND                      PC228            2        Q_CAP_C0805-22UF,10V,20%,X6S,CA
GND                      PC229            2        Q_CAP_C0805-22UF,10V,20%,X6S,CA
GND                      PC233            2        Q_CAP_C0402-1UF,25V,10%,X6S,CHA
GND                      PC235            2        Q_CAP_0402-0.1UF,25V,10%,X7R,CA
GND                      PC237            2        Q_CAP_C0805-10UF,25V,10%,X6S,CA
GND                      PC242            2        Q_CAP_C0805-10UF,25V,10%,X6S,CA
GND                      PC243            2        Q_CAP_C0402-1UF,25V,10%,X6S,CHA
GND                      PC248            2        Q_CAP_C0805-10UF,25V,10%,X6S,CA
GND                      PC249            2        Q_CAP_0402-0.1UF,25V,10%,X7R,CA
GND                      PC250            2        Q_CAP_C0402-1UF,25V,10%,X6S,CHA
GND                      PC251            2        Q_CAP_C0805-10UF,25V,10%,X6S,CA
GND                      PC252            2        Q_CAP_C0805-10UF,25V,10%,X6S,CA
GND                      PC253            2        Q_CAP_0402-0.1UF,25V,10%,X7R,CA
GND                      PC255            2        Q_CAP_0402-0.1UF,25V,10%,X7R,CA
GND                      PC256            2        Q_CAP_0805-22UF,4V,20%,X6S,TMPA
GND                      PC257            2        Q_CAP_0805-22UF,4V,20%,X6S,TMPA
GND                      PC258            2        Q_CAP_0805-22UF,4V,20%,X6S,TMPA
GND                      PC259            2        Q_CAP_0805-22UF,4V,20%,X6S,TMPA
GND                      PC260            2        Q_CAP_C0402-1UF,25V,10%,X6S,CHA
GND                      PC261            2        Q_CAP_C0805-10UF,25V,10%,X6S,CA
GND                      PC262            2        Q_CAP_C0805-10UF,25V,10%,X6S,CA
GND                      PC263            2        Q_CAP_0402-0.1UF,25V,10%,X7R,CA
GND                      PC266            2        Q_CAP_0402-0.1UF,25V,10%,X7R,CA
GND                      PC267            2        Q_CAP_0805-22UF,4V,20%,X6S,TMPA
GND                      PC268            2        Q_CAP_0805-22UF,4V,20%,X6S,TMPA
GND                      PC269            2        Q_CAP_0805-22UF,4V,20%,X6S,TMPA
GND                      PC270            2        Q_CAP_0805-22UF,4V,20%,X6S,TMPA
GND                      PC271            2        Q_CAP_0402-0.1UF,25V,10%,X7R,CA
GND                      PC273            2        Q_CAP_0402-3300PF,50V,10%,X7R,A
GND                      PC307            2        Q_CAP_C0805-10UF,25V,10%,X6S,CA
GND                      PR245            2        Q_RES_0402LF-100K,1%,1/16W,CHIA
GND                      PR276            1        Q_RES_0402LF-8.66K,1%,1/16W,CHA
GND                      PR496            2        Q_RES_0402LF-150K,1%,1/16W,CHIA
GND                      PR522            2        Q_RES_0402LF-100K,1%,1/16W,CHIA
GND                      PR525            2        Q_RES_0402LF-13.3K,1%,1/16W,CHA
GND                      PR526            2        Q_RES_0402LF-12.4K,1%,1/16W,CHA
GND                      PR530            1        Q_RES_0402LF-12.4K,1%,1/16W,CHA
GND                      PR532            1        Q_RES_0402LF-60.4K,1%,1/16W,CHA
GND                      PR543            2        Q_RES_0402LF-100K,0.1%,1/16W,CA
GND                      PU1              1        MPQ8626GDZ-MPQ8626GD-Z,SMLF,ICA
GND                      PU1              7        MPQ8626GDZ-MPQ8626GD-Z,SMLF,ICA
GND                      PU1              14       MPQ8626GDZ-MPQ8626GD-Z,SMLF,ICA
GND                      PU38             11_18    MPQ8633AGLEC807Z-MPQ8633AGLE-CA
GND                      PU38             2        MPQ8633AGLEC807Z-MPQ8633AGLE-CA
GND                      PU38             4        MPQ8633AGLEC807Z-MPQ8633AGLE-CA
GND                      PU38             6        MPQ8633AGLEC807Z-MPQ8633AGLE-CA
GND                      PU39             TH       RT9059GQW-RT9059GQW,SMLF,IC,ALA
GND                      PU40             TH       RT9059GQW-RT9059GQW,SMLF,IC,ALA
GND                      PU41             2        NB695GDZ-NB695GD-Z,SMLF,IC,AL0A
GND                      PU41             3        NB695GDZ-NB695GD-Z,SMLF,IC,AL0A
GND                      PU41             4        NB695GDZ-NB695GD-Z,SMLF,IC,AL0A
GND                      PU41             11       NB695GDZ-NB695GD-Z,SMLF,IC,AL0A
GND                      PU42             2        NB695GDZ-NB695GD-Z,SMLF,IC,AL0A
GND                      PU42             4        NB695GDZ-NB695GD-Z,SMLF,IC,AL0A
GND                      PU42             11       NB695GDZ-NB695GD-Z,SMLF,IC,AL0A
GND                      Q1               E        MMBT39047F-MMBT3904-7-F,SMLF,IA
GND                      Q3               E        MMBT39047F-MMBT3904-7-F,SMLF,IA
GND                      Q9               S        MOSFET_N_GSD-DMG6968U-7,SMLF,IA
GND                      Q10              S        MOSFET_N_GSD-DMG6968U-7,SMLF,IA
GND                      Q12              1        MOSFET_DUAL_6P-2N7002KDW,SMLF,A
GND                      R2               2        Q_RES_0402LF-0,5%,1/16W,CHIP,CA
GND                      R3               2        Q_RES_0402LF-0,5%,1/16W,CHIP,CA
GND                      R4               2        Q_RES_0402LF-1K,1%,1/16W,CHIP,A
GND                      R5               2        Q_RES_0402LF-1K,1%,1/16W,CHIP,A
GND                      R6               2        Q_RES_0402LF-240,1%,1/16W,CHIPA
GND                      R15              2        Q_RES_0402LF-1K,1%,1/16W,CHIP,A
GND                      R22              2        Q_RES_0402LF-150,1%,1/16W,CHIPA
GND                      R23              2        Q_RES_0402LF-150,1%,1/16W,CHIPA
GND                      R25              2        Q_RES_0402LF-150,1%,1/16W,CHIPA
GND                      R40              1        Q_RES_0402LF-2K,1%,1/16W,EMPTYA
GND                      R63              2        Q_RES_0402LF-0,5%,1/16W,EMPTY,A
GND                      R64              2        Q_RES_0402LF-0,5%,1/16W,EMPTY,A
GND                      R66              1        Q_RES_0402LF-100K,1%,1/16W,CHIA
GND                      R87              2        Q_RES_0402LF-150,1%,1/16W,CHIPA
GND                      R88              2        Q_RES_0402LF-150,1%,1/16W,CHIPA
GND                      R89              2        Q_RES_0402LF-150,1%,1/16W,CHIPA
GND                      R94              2        Q_RES_0402LF-100,1%,1/16W,CHIPA
GND                      R118             1        Q_RES_0402LF-100K,1%,1/16W,EMPA
GND                      R127             1        Q_RES_0402LF-240,1%,1/16W,CHIPA
GND                      R202             1        Q_RES_0402LF-10K,0.10%,1/16W,CA
GND                      R205             2        Q_RES_0402LF-20K,1%,1/16W,CHIPA
GND                      R206             1        Q_RES_0402LF-47K,5%,1/16W,EMPTA
GND                      R209             2        Q_RES_0402LF-10K,1%,1/16W,CHIPA
GND                      R210             1        Q_RES_0402LF-10K,1%,1/16W,CHIPA
GND                      R219             2        Q_RES_0402LF-100K,1%,1/16W,EMPB
GND                      R220             2        Q_RES_0402LF-0,5%,1/16W,CHIP,CA
GND                      R228             1        Q_RES_0402LF-10K,0.10%,1/16W,CA
GND                      R229             1        Q_RES_0402LF-4.7K,1%,1/16W,EMPA
GND                      R233             1        Q_RES_0402LF -49.9K,1%,1/16W ,A
GND                      R234             1        Q_RES_0402LF -49.9K,1%,1/16W ,A
GND                      R235             1        Q_RES_0402LF-2.74K,1%,1/16W,CHA
GND                      R296             2        Q_RES_0402LF-100K,1%,1/16W,EMPB
GND                      R308             2        Q_RES_0402LF-4.7K,1%,1/16W,EMPA
GND                      R310             2        Q_RES_0402LF-4.7K,1%,1/16W,EMPA
GND                      R312             2        Q_RES_0402LF-4.7K,1%,1/16W,EMPA
GND                      R313             2        Q_RES_0402LF-470K,1%,1/16W,CHIA
GND                      R314             2        Q_RES_0402LF-100K,1%,1/16W,CHIB
GND                      R325             2        Q_RES_0402LF-1K,1%,1/16W,CHIP,A
GND                      R326             1        Q_RES_0402LF-120,1%,1/16W,CHIPA
GND                      R327             1        Q_RES_0402LF-120,1%,1/16W,CHIPA
GND                      R328             1        Q_RES_0402LF-120,1%,1/16W,CHIPA
GND                      R329             1        Q_RES_0402LF-120,1%,1/16W,CHIPA
GND                      R330             1        Q_RES_0402LF-120,1%,1/16W,CHIPA
GND                      R331             1        Q_RES_0402LF-120,1%,1/16W,CHIPA
GND                      R332             1        Q_RES_0402LF-120,1%,1/16W,CHIPA
GND                      R333             1        Q_RES_0402LF-120,1%,1/16W,CHIPA
GND                      R334             1        Q_RES_0402LF-120,1%,1/16W,CHIPA
GND                      R335             1        Q_RES_0402LF-120,1%,1/16W,CHIPA
GND                      R336             1        Q_RES_0402LF-120,1%,1/16W,CHIPA
GND                      R337             1        Q_RES_0402LF-120,1%,1/16W,CHIPA
GND                      R338             1        Q_RES_0402LF-120,1%,1/16W,CHIPA
GND                      R339             1        Q_RES_0402LF-120,1%,1/16W,CHIPA
GND                      R340             1        Q_RES_0402LF-120,1%,1/16W,CHIPA
GND                      R341             1        Q_RES_0402LF-120,1%,1/16W,CHIPA
GND                      R342             1        Q_RES_0402LF-120,1%,1/16W,CHIPA
GND                      R343             1        Q_RES_0402LF-120,1%,1/16W,CHIPA
GND                      R344             1        Q_RES_0402LF-120,1%,1/16W,CHIPA
GND                      R345             1        Q_RES_0402LF-120,1%,1/16W,CHIPA
GND                      R346             1        Q_RES_0402LF-120,1%,1/16W,CHIPA
GND                      R347             1        Q_RES_0402LF-120,1%,1/16W,CHIPA
GND                      R348             1        Q_RES_0402LF-120,1%,1/16W,CHIPA
GND                      R349             1        Q_RES_0402LF-120,1%,1/16W,CHIPA
GND                      R350             1        Q_RES_0402LF-120,1%,1/16W,EMPTA
GND                      R377             2        Q_RES_0402LF-10K,1%,1/16W,EMPTB
GND                      R378             2        Q_RES_0402LF-20K,1%,1/16W,CHIPA
GND                      R388             2        Q_RES_0402LF-4.7K,1%,1/16W,EMPA
GND                      R390             2        Q_RES_0402LF-4.7K,1%,1/16W,EMPA
GND                      R391             2        Q_RES_0402LF-100K,1%,1/16W,CHIA
GND                      R392             2        Q_RES_0402LF-100K,1%,1/16W,CHIA
GND                      R395             2        Q_RES_0402LF-1M,1%,1/16W,CHIP,A
GND                      R396             2        Q_RES_0402LF-1M,1%,1/16W,CHIP,A
GND                      R400             2        Q_RES_0402LF-1.24K,1%,1/16W,CHA
GND                      R411             2        Q_RES_0402LF-100,1%,1/16W,EMPTA
GND                      R412             2        Q_RES_0402LF-100,1%,1/16W,CHIPA
GND                      R413             2        Q_RES_0402LF-100,1%,1/16W,CHIPA
GND                      R415             2        Q_RES_0402LF-100,1%,1/16W,CHIPA
GND                      R417             2        Q_RES_0402LF-100,1%,1/16W,EMPTA
GND                      R419             2        Q_RES_0402LF-100,1%,1/16W,CHIPA
GND                      R431             2        Q_RES_0402LF-100,1%,1/16W,CHIPA
GND                      R467             2        Q_RES_0402LF-2K,1%,1/16W,CHIP,A
GND                      R487             2        Q_RES_0402LF-4.7K,1%,1/16W,EMPA
GND                      R506             2        Q_RES_0402LF-100,1%,1/16W,CHIPA
GND                      R507             2        Q_RES_0402LF-100,1%,1/16W,CHIPA
GND                      R614             2        Q_RES_0402LF-100K,1%,1/16W,CHIA
GND                      R618             1        Q_RES_0402LF-10K,1%,1/16W,CHIPA
GND                      R620             2        Q_RES_0402LF-100K,1%,1/16W,CHIA
GND                      R684             2        Q_RES_0402LF-1K,1%,1/16W,EMPTYA
GND                      R685             2        Q_RES_0402LF-1K,1%,1/16W,EMPTYA
GND                      R776             2        Q_RES_0201LF-47K,1%,1/20W,CHIPA
GND                      R778             2        Q_RES_0402LF-100K,1%,1/16W,CHIA
GND                      R786             2        Q_RES_0402LF-2K,1%,1/16W,CHIP,A
GND                      R788             2        Q_RES_0402LF-2K,1%,1/16W,CHIP,A
GND                      R790             2        Q_RES_0402LF-2K,1%,1/16W,CHIP,A
GND                      R792             2        Q_RES_0402LF-2K,1%,1/16W,CHIP,A
GND                      R794             2        Q_RES_0402LF-2K,1%,1/16W,CHIP,A
GND                      R798             2        Q_RES_0402LF-2K,1%,1/16W,CHIP,A
GND                      R811             2        Q_RES_0402LF-10K,0.10%,1/16W,CA
GND                      R817             2        Q_RES_0402LF-100K,1%,1/16W,EMPB
GND                      R818             2        Q_RES_0402LF-100K,1%,1/16W,EMPB
GND                      R819             2        Q_RES_0402LF-100K,1%,1/16W,EMPB
GND                      R820             2        Q_RES_0402LF-100K,1%,1/16W,EMPB
GND                      R823             1        Q_RES_0402LF-100K,1%,1/16W,CHIA
GND                      R830             2        Q_RES_0402LF-12K,1%,1/16W,CHIPA
GND                      R832             2        Q_RES_0402LF-12K,1%,1/16W,CHIPA
GND                      R839             2        Q_RES_0402LF-8.2K     ,5%  ,1/A
GND                      R866             2        Q_RES_0402LF-10K,1%,1/16W,CHIPA
GND                      SW6              1        SW2S_TA31E2KQTR-SW2S_TA3-1E2K-A
GND                      SW6              G1       SW2S_TA31E2KQTR-SW2S_TA3-1E2K-A
GND                      SW6              G2       SW2S_TA31E2KQTR-SW2S_TA3-1E2K-A
GND                      SW6              G3       SW2S_TA31E2KQTR-SW2S_TA3-1E2K-A
GND                      SW7              1        SW2S_TA31E2KQTR-SW2S_TA3-1E2K-A
GND                      SW7              G1       SW2S_TA31E2KQTR-SW2S_TA3-1E2K-A
GND                      SW7              G2       SW2S_TA31E2KQTR-SW2S_TA3-1E2K-A
GND                      SW7              G3       SW2S_TA31E2KQTR-SW2S_TA3-1E2K-A
GND                      U1               A2       K4A8G165WCBCTD-K4A8G165WC-BCTDA
GND                      U1               A8       K4A8G165WCBCTD-K4A8G165WC-BCTDA
GND                      U1               B2       K4A8G165WCBCTD-K4A8G165WC-BCTDA
GND                      U1               C9       K4A8G165WCBCTD-K4A8G165WC-BCTDA
GND                      U1               D2       K4A8G165WCBCTD-K4A8G165WC-BCTDA
GND                      U1               D8       K4A8G165WCBCTD-K4A8G165WC-BCTDA
GND                      U1               E1       K4A8G165WCBCTD-K4A8G165WC-BCTDA
GND                      U1               E3       K4A8G165WCBCTD-K4A8G165WC-BCTDA
GND                      U1               E8       K4A8G165WCBCTD-K4A8G165WC-BCTDA
GND                      U1               F1       K4A8G165WCBCTD-K4A8G165WC-BCTDA
GND                      U1               G8       K4A8G165WCBCTD-K4A8G165WC-BCTDA
GND                      U1               H1       K4A8G165WCBCTD-K4A8G165WC-BCTDA
GND                      U1               H9       K4A8G165WCBCTD-K4A8G165WC-BCTDA
GND                      U1               K1       K4A8G165WCBCTD-K4A8G165WC-BCTDA
GND                      U1               K9       K4A8G165WCBCTD-K4A8G165WC-BCTDA
GND                      U1               N1       K4A8G165WCBCTD-K4A8G165WC-BCTDA
GND                      U1               T1       K4A8G165WCBCTD-K4A8G165WC-BCTDA
GND                      U1               T7       K4A8G165WCBCTD-K4A8G165WC-BCTDA
GND                      U2               2        SN74LVC1G3157DCKR-SN74LVC1G315A
GND                      U3               2        SN74LVC1G3157DCKR-SN74LVC1G315A
GND                      U4               4        TMP75AIDGKR-TMP75AIDGKR,SMLF,IA
GND                      U5               A1       AST2600A1GP-AST2600A1-GP,SMLF,A
GND                      U5               A2       AST2600A1GP-AST2600A1-GP,SMLF,A
GND                      U5               A3       AST2600A1GP-AST2600A1-GP,SMLF,A
GND                      U5               A5       AST2600A1GP-AST2600A1-GP,SMLF,A
GND                      U5               A26      AST2600A1GP-AST2600A1-GP,SMLF,A
GND                      U5               AA1      AST2600A1GP-AST2600A1-GP,SMLF,A
GND                      U5               AA3      AST2600A1GP-AST2600A1-GP,SMLF,A
GND                      U5               AA6      AST2600A1GP-AST2600A1-GP,SMLF,A
GND                      U5               AA7      AST2600A1GP-AST2600A1-GP,SMLF,A
GND                      U5               AA8      AST2600A1GP-AST2600A1-GP,SMLF,A
GND                      U5               AA10     AST2600A1GP-AST2600A1-GP,SMLF,A
GND                      U5               AA14     AST2600A1GP-AST2600A1-GP,SMLF,A
GND                      U5               AA15     AST2600A1GP-AST2600A1-GP,SMLF,A
GND                      U5               AA19     AST2600A1GP-AST2600A1-GP,SMLF,A
GND                      U5               AA20     AST2600A1GP-AST2600A1-GP,SMLF,A
GND                      U5               AA22     AST2600A1GP-AST2600A1-GP,SMLF,A
GND                      U5               AC2      AST2600A1GP-AST2600A1-GP,SMLF,A
GND                      U5               AC6      AST2600A1GP-AST2600A1-GP,SMLF,A
GND                      U5               AC25     AST2600A1GP-AST2600A1-GP,SMLF,A
GND                      U5               AD1      AST2600A1GP-AST2600A1-GP,SMLF,A
GND                      U5               AD4      AST2600A1GP-AST2600A1-GP,SMLF,A
GND                      U5               AE3      AST2600A1GP-AST2600A1-GP,SMLF,A
GND                      U5               AE6      AST2600A1GP-AST2600A1-GP,SMLF,A
GND                      U5               AE9      AST2600A1GP-AST2600A1-GP,SMLF,A
GND                      U5               AE13     AST2600A1GP-AST2600A1-GP,SMLF,A
GND                      U5               AE17     AST2600A1GP-AST2600A1-GP,SMLF,A
GND                      U5               AE20     AST2600A1GP-AST2600A1-GP,SMLF,A
GND                      U5               AE23     AST2600A1GP-AST2600A1-GP,SMLF,A
GND                      U5               AF1      AST2600A1GP-AST2600A1-GP,SMLF,A
GND                      U5               AF4      AST2600A1GP-AST2600A1-GP,SMLF,A
GND                      U5               AF26     AST2600A1GP-AST2600A1-GP,SMLF,A
GND                      U5               B1       AST2600A1GP-AST2600A1-GP,SMLF,A
GND                      U5               B2       AST2600A1GP-AST2600A1-GP,SMLF,A
GND                      U5               B3       AST2600A1GP-AST2600A1-GP,SMLF,A
GND                      U5               B5       AST2600A1GP-AST2600A1-GP,SMLF,A
GND                      U5               B11      AST2600A1GP-AST2600A1-GP,SMLF,A
GND                      U5               B15      AST2600A1GP-AST2600A1-GP,SMLF,A
GND                      U5               B19      AST2600A1GP-AST2600A1-GP,SMLF,A
GND                      U5               B23      AST2600A1GP-AST2600A1-GP,SMLF,A
GND                      U5               C1       AST2600A1GP-AST2600A1-GP,SMLF,A
GND                      U5               C2       AST2600A1GP-AST2600A1-GP,SMLF,A
GND                      U5               C3       AST2600A1GP-AST2600A1-GP,SMLF,A
GND                      U5               C4       AST2600A1GP-AST2600A1-GP,SMLF,A
GND                      U5               C5       AST2600A1GP-AST2600A1-GP,SMLF,A
GND                      U5               C6       AST2600A1GP-AST2600A1-GP,SMLF,A
GND                      U5               C26      AST2600A1GP-AST2600A1-GP,SMLF,A
GND                      U5               D1       AST2600A1GP-AST2600A1-GP,SMLF,A
GND                      U5               D2       AST2600A1GP-AST2600A1-GP,SMLF,A
GND                      U5               D3       AST2600A1GP-AST2600A1-GP,SMLF,A
GND                      U5               D4       AST2600A1GP-AST2600A1-GP,SMLF,A
GND                      U5               D5       AST2600A1GP-AST2600A1-GP,SMLF,A
GND                      U5               D6       AST2600A1GP-AST2600A1-GP,SMLF,A
GND                      U5               D25      AST2600A1GP-AST2600A1-GP,SMLF,A
GND                      U5               E1       AST2600A1GP-AST2600A1-GP,SMLF,A
GND                      U5               E2       AST2600A1GP-AST2600A1-GP,SMLF,A
GND                      U5               E3       AST2600A1GP-AST2600A1-GP,SMLF,A
GND                      U5               E4       AST2600A1GP-AST2600A1-GP,SMLF,A
GND                      U5               E5       AST2600A1GP-AST2600A1-GP,SMLF,A
GND                      U5               E6       AST2600A1GP-AST2600A1-GP,SMLF,A
GND                      U5               E8       AST2600A1GP-AST2600A1-GP,SMLF,A
GND                      U5               F4       AST2600A1GP-AST2600A1-GP,SMLF,A
GND                      U5               F5       AST2600A1GP-AST2600A1-GP,SMLF,A
GND                      U5               F6       AST2600A1GP-AST2600A1-GP,SMLF,A
GND                      U5               F8       AST2600A1GP-AST2600A1-GP,SMLF,A
GND                      U5               F10      AST2600A1GP-AST2600A1-GP,SMLF,A
GND                      U5               F12      AST2600A1GP-AST2600A1-GP,SMLF,A
GND                      U5               F14      AST2600A1GP-AST2600A1-GP,SMLF,A
GND                      U5               F16      AST2600A1GP-AST2600A1-GP,SMLF,A
GND                      U5               F17      AST2600A1GP-AST2600A1-GP,SMLF,A
GND                      U5               F18      AST2600A1GP-AST2600A1-GP,SMLF,A
GND                      U5               F21      AST2600A1GP-AST2600A1-GP,SMLF,A
GND                      U5               G2       AST2600A1GP-AST2600A1-GP,SMLF,A
GND                      U5               G25      AST2600A1GP-AST2600A1-GP,SMLF,A
GND                      U5               H4       AST2600A1GP-AST2600A1-GP,SMLF,A
GND                      U5               H9       AST2600A1GP-AST2600A1-GP,SMLF,A
GND                      U5               H10      AST2600A1GP-AST2600A1-GP,SMLF,A
GND                      U5               H11      AST2600A1GP-AST2600A1-GP,SMLF,A
GND                      U5               H13      AST2600A1GP-AST2600A1-GP,SMLF,A
GND                      U5               J2       AST2600A1GP-AST2600A1-GP,SMLF,A
GND                      U5               J11      AST2600A1GP-AST2600A1-GP,SMLF,A
GND                      U5               J13      AST2600A1GP-AST2600A1-GP,SMLF,A
GND                      U5               J14      AST2600A1GP-AST2600A1-GP,SMLF,A
GND                      U5               J15      AST2600A1GP-AST2600A1-GP,SMLF,A
GND                      U5               J16      AST2600A1GP-AST2600A1-GP,SMLF,A
GND                      U5               J17      AST2600A1GP-AST2600A1-GP,SMLF,A
GND                      U5               J18      AST2600A1GP-AST2600A1-GP,SMLF,A
GND                      U5               J19      AST2600A1GP-AST2600A1-GP,SMLF,A
GND                      U5               K4       AST2600A1GP-AST2600A1-GP,SMLF,A
GND                      U5               K8       AST2600A1GP-AST2600A1-GP,SMLF,A
GND                      U5               K9       AST2600A1GP-AST2600A1-GP,SMLF,A
GND                      U5               K13      AST2600A1GP-AST2600A1-GP,SMLF,A
GND                      U5               K14      AST2600A1GP-AST2600A1-GP,SMLF,A
GND                      U5               K15      AST2600A1GP-AST2600A1-GP,SMLF,A
GND                      U5               K22      AST2600A1GP-AST2600A1-GP,SMLF,A
GND                      U5               L2       AST2600A1GP-AST2600A1-GP,SMLF,A
GND                      U5               L8       AST2600A1GP-AST2600A1-GP,SMLF,A
GND                      U5               L11      AST2600A1GP-AST2600A1-GP,SMLF,A
GND                      U5               L12      AST2600A1GP-AST2600A1-GP,SMLF,A
GND                      U5               L15      AST2600A1GP-AST2600A1-GP,SMLF,A
GND                      U5               L16      AST2600A1GP-AST2600A1-GP,SMLF,A
GND                      U5               L17      AST2600A1GP-AST2600A1-GP,SMLF,A
GND                      U5               L18      AST2600A1GP-AST2600A1-GP,SMLF,A
GND                      U5               L19      AST2600A1GP-AST2600A1-GP,SMLF,A
GND                      U5               L25      AST2600A1GP-AST2600A1-GP,SMLF,A
GND                      U5               M4       AST2600A1GP-AST2600A1-GP,SMLF,A
GND                      U5               M9       AST2600A1GP-AST2600A1-GP,SMLF,A
GND                      U5               M10      AST2600A1GP-AST2600A1-GP,SMLF,A
GND                      U5               M12      AST2600A1GP-AST2600A1-GP,SMLF,A
GND                      U5               M15      AST2600A1GP-AST2600A1-GP,SMLF,A
GND                      U5               M16      AST2600A1GP-AST2600A1-GP,SMLF,A
GND                      U5               M17      AST2600A1GP-AST2600A1-GP,SMLF,A
GND                      U5               M18      AST2600A1GP-AST2600A1-GP,SMLF,A
GND                      U5               M19      AST2600A1GP-AST2600A1-GP,SMLF,A
GND                      U5               N2       AST2600A1GP-AST2600A1-GP,SMLF,A
GND                      U5               N6       AST2600A1GP-AST2600A1-GP,SMLF,A
GND                      U5               N9       AST2600A1GP-AST2600A1-GP,SMLF,A
GND                      U5               N10      AST2600A1GP-AST2600A1-GP,SMLF,A
GND                      U5               N15      AST2600A1GP-AST2600A1-GP,SMLF,A
GND                      U5               N16      AST2600A1GP-AST2600A1-GP,SMLF,A
GND                      U5               N17      AST2600A1GP-AST2600A1-GP,SMLF,A
GND                      U5               N18      AST2600A1GP-AST2600A1-GP,SMLF,A
GND                      U5               N19      AST2600A1GP-AST2600A1-GP,SMLF,A
GND                      U5               P4       AST2600A1GP-AST2600A1-GP,SMLF,A
GND                      U5               P9       AST2600A1GP-AST2600A1-GP,SMLF,A
GND                      U5               P10      AST2600A1GP-AST2600A1-GP,SMLF,A
GND                      U5               P15      AST2600A1GP-AST2600A1-GP,SMLF,A
GND                      U5               P16      AST2600A1GP-AST2600A1-GP,SMLF,A
GND                      U5               P17      AST2600A1GP-AST2600A1-GP,SMLF,A
GND                      U5               P18      AST2600A1GP-AST2600A1-GP,SMLF,A
GND                      U5               P19      AST2600A1GP-AST2600A1-GP,SMLF,A
GND                      U5               R2       AST2600A1GP-AST2600A1-GP,SMLF,A
GND                      U5               R8       AST2600A1GP-AST2600A1-GP,SMLF,A
GND                      U5               R11      AST2600A1GP-AST2600A1-GP,SMLF,A
GND                      U5               R15      AST2600A1GP-AST2600A1-GP,SMLF,A
GND                      U5               R16      AST2600A1GP-AST2600A1-GP,SMLF,A
GND                      U5               R17      AST2600A1GP-AST2600A1-GP,SMLF,A
GND                      U5               R18      AST2600A1GP-AST2600A1-GP,SMLF,A
GND                      U5               R19      AST2600A1GP-AST2600A1-GP,SMLF,A
GND                      U5               R25      AST2600A1GP-AST2600A1-GP,SMLF,A
GND                      U5               T4       AST2600A1GP-AST2600A1-GP,SMLF,A
GND                      U5               T11      AST2600A1GP-AST2600A1-GP,SMLF,A
GND                      U5               T12      AST2600A1GP-AST2600A1-GP,SMLF,A
GND                      U5               T15      AST2600A1GP-AST2600A1-GP,SMLF,A
GND                      U5               T16      AST2600A1GP-AST2600A1-GP,SMLF,A
GND                      U5               T17      AST2600A1GP-AST2600A1-GP,SMLF,A
GND                      U5               T18      AST2600A1GP-AST2600A1-GP,SMLF,A
GND                      U5               T19      AST2600A1GP-AST2600A1-GP,SMLF,A
GND                      U5               U2       AST2600A1GP-AST2600A1-GP,SMLF,A
GND                      U5               U8       AST2600A1GP-AST2600A1-GP,SMLF,A
GND                      U5               U9       AST2600A1GP-AST2600A1-GP,SMLF,A
GND                      U5               U10      AST2600A1GP-AST2600A1-GP,SMLF,A
GND                      U5               U11      AST2600A1GP-AST2600A1-GP,SMLF,A
GND                      U5               U12      AST2600A1GP-AST2600A1-GP,SMLF,A
GND                      U5               U14      AST2600A1GP-AST2600A1-GP,SMLF,A
GND                      U5               U19      AST2600A1GP-AST2600A1-GP,SMLF,A
GND                      U5               U22      AST2600A1GP-AST2600A1-GP,SMLF,A
GND                      U5               U23      AST2600A1GP-AST2600A1-GP,SMLF,A
GND                      U5               V5       AST2600A1GP-AST2600A1-GP,SMLF,A
GND                      U5               V11      AST2600A1GP-AST2600A1-GP,SMLF,A
GND                      U5               V12      AST2600A1GP-AST2600A1-GP,SMLF,A
GND                      U5               V14      AST2600A1GP-AST2600A1-GP,SMLF,A
GND                      U5               V15      AST2600A1GP-AST2600A1-GP,SMLF,A
GND                      U5               V16      AST2600A1GP-AST2600A1-GP,SMLF,A
GND                      U5               V17      AST2600A1GP-AST2600A1-GP,SMLF,A
GND                      U5               V18      AST2600A1GP-AST2600A1-GP,SMLF,A
GND                      U5               V19      AST2600A1GP-AST2600A1-GP,SMLF,A
GND                      U5               W5       AST2600A1GP-AST2600A1-GP,SMLF,A
GND                      U5               W6       AST2600A1GP-AST2600A1-GP,SMLF,A
GND                      U5               W8       AST2600A1GP-AST2600A1-GP,SMLF,A
GND                      U5               W9       AST2600A1GP-AST2600A1-GP,SMLF,A
GND                      U5               W10      AST2600A1GP-AST2600A1-GP,SMLF,A
GND                      U5               W11      AST2600A1GP-AST2600A1-GP,SMLF,A
GND                      U5               W12      AST2600A1GP-AST2600A1-GP,SMLF,A
GND                      U5               W22      AST2600A1GP-AST2600A1-GP,SMLF,A
GND                      U5               W25      AST2600A1GP-AST2600A1-GP,SMLF,A
GND                      U5               Y6       AST2600A1GP-AST2600A1-GP,SMLF,A
GND                      U5               Y22      AST2600A1GP-AST2600A1-GP,SMLF,A
GND                      U6               2        SN74LVC2G07DCKR_SMLF-SN74LVC2GA
GND                      U7               5        BCM54612EB1KMLG-BCM54612EB1KMLA
GND                      U7               6        BCM54612EB1KMLG-BCM54612EB1KMLA
GND                      U7               TH       BCM54612EB1KMLG-BCM54612EB1KMLA
GND                      U8               2        TPD4E001DBVR-TPD4E001DBVR,SMLFB
GND                      U9               2        TPD4E001DBVR-TPD4E001DBVR,SMLFB
GND                      U10              2        TPS2553DBVR1-TPS2553DBVR-1,SMLA
GND                      U12              S        MOSFET_N_SMLF-BSS138K,BSS138K,A
GND                      U13              3        SN74LVC1G07DCKR-SN74LVC1G07DCKA
GND                      U14              2        AP22811AW57-AP22811AW5-7,SMLF,A
GND                      U15              5        TPS22965DSGR-TPS22965DSGR,SMLFA
GND                      U15              TH       TPS22965DSGR-TPS22965DSGR,SMLFA
GND                      U16              2        TPD4E001DBVR-TPD4E001DBVR,SMLFA
GND                      U17              5        FT234XDR-FT234XD-R,SMLF,IC,AL0A
GND                      U17              13       FT234XDR-FT234XD-R,SMLF,IC,AL0A
GND                      U18              3        TPD2EUSB30DRTR_SMLF-TPD2EUSB30A
GND                      U19              4        M24128BWDW6TP-M24128-BWDW6TP,SA
GND                      U20              A6       MTFC8GAKAJCN1MWT-MTFC8GAKAJCN-A
GND                      U20              C4       MTFC8GAKAJCN1MWT-MTFC8GAKAJCN-A
GND                      U20              E7       MTFC8GAKAJCN1MWT-MTFC8GAKAJCN-A
GND                      U20              G5       MTFC8GAKAJCN1MWT-MTFC8GAKAJCN-A
GND                      U20              H10      MTFC8GAKAJCN1MWT-MTFC8GAKAJCN-A
GND                      U20              J5       MTFC8GAKAJCN1MWT-MTFC8GAKAJCN-A
GND                      U20              K8       MTFC8GAKAJCN1MWT-MTFC8GAKAJCN-A
GND                      U20              N2       MTFC8GAKAJCN1MWT-MTFC8GAKAJCN-A
GND                      U20              N5       MTFC8GAKAJCN1MWT-MTFC8GAKAJCN-A
GND                      U20              P4       MTFC8GAKAJCN1MWT-MTFC8GAKAJCN-A
GND                      U20              P6       MTFC8GAKAJCN1MWT-MTFC8GAKAJCN-A
GND                      U21              8        IDTQS3VH257PAG_SMLF-IDTQS3VH25A
GND                      U23              3        SN74LVC1G07DBVR_SMLF-SN74LVC1GA
GND                      U24              2        SN74LVC2G07DCKR_SMLF-SN74LVC2GA
GND                      U25              A1       10M02SCU169C8G-10M02SCU169C8G,A
GND                      U25              A13      10M02SCU169C8G-10M02SCU169C8G,A
GND                      U25              B8       10M02SCU169C8G-10M02SCU169C8G,A
GND                      U25              C3       10M02SCU169C8G-10M02SCU169C8G,A
GND                      U25              D5       10M02SCU169C8G-10M02SCU169C8G,A
GND                      U25              E11      10M02SCU169C8G-10M02SCU169C8G,A
GND                      U25              F3       10M02SCU169C8G-10M02SCU169C8G,A
GND                      U25              G7       10M02SCU169C8G-10M02SCU169C8G,A
GND                      U25              H12      10M02SCU169C8G-10M02SCU169C8G,A
GND                      U25              J4       10M02SCU169C8G-10M02SCU169C8G,A
GND                      U25              L9       10M02SCU169C8G-10M02SCU169C8G,A
GND                      U25              M6       10M02SCU169C8G-10M02SCU169C8G,A
GND                      U25              N1       10M02SCU169C8G-10M02SCU169C8G,A
GND                      U25              N13      10M02SCU169C8G-10M02SCU169C8G,A
GND                      U26              3        74HC1G126GW-74HC1G126GW,SMLF,IA
GND                      U28              10       MX66L1G45GMI08G-MX66L1G45GMI-0A
GND                      U29              3        74HC1G126GW-74HC1G126GW,SMLF,IA
GND                      U30              8        IDTQS3VH257PAG_SMLF-IDTQS3VH25A
GND                      U31              3        74LVC1G07GW-74LVC1G07GW,SMLF,IA
GND                      U32              3        74LVC1G17GW-74LVC1G17GW,SMLF,IA
GND                      U33              3        74HC1G126GW-74HC1G126GW,SMLF,IA
GND                      U34              2        TPD4E001DBVR-TPD4E001DBVR,SMLFA
GND                      U35              2        TPD4E001DBVR-TPD4E001DBVR,SMLFA
GND                      U36              3        74HC1G126GW-74HC1G126GW,SMLF,IA
GND                      U38              1        PRTR5V0U2X-PRTR5V0U2X,SMLF,IC,A
GND                      U43              2        TPS3808G33DBVR-TPS3808G33DBVR,A
GND                      Y1               2        Q_XTAL_4P_13BI_24GND-25MHZ,SMLA
GND                      Y1               4        Q_XTAL_4P_13BI_24GND-25MHZ,SMLA
GND_P1                   J9               3        DELTA_L-DELTA-L,THLF,EMPTY,TP24
GND_P1                   J12              3        DELTA_L-DELTA-L,THLF,EMPTY,TP24
GND_P1                   J17              3        DELTA_L-DELTA-L,THLF,EMPTY,TP24
GND_P1                   J20              3        DELTA_L-DELTA-L,THLF,EMPTY,TP24
GND_P1                   J22              3        DELTA_L-DELTA-L,THLF,EMPTY,TP24
GND_P1                   J24              3        DELTA_L-DELTA-L,THLF,EMPTY,TP24
GND_P1                   J25              3        DELTA_L-DELTA-L,THLF,EMPTY,TP24
GND_P1                   J27              3        DELTA_L-DELTA-L,THLF,EMPTY,TP24
GND_P1                   J28              3        DELTA_L-DELTA-L,THLF,EMPTY,TP24
GND_P1                   J30              3        DELTA_L-DELTA-L,THLF,EMPTY,TP24
GND_P2                   J11              3        DELTA_L-DELTA-L,THLF,EMPTY,TP24
GND_P2                   J16              3        DELTA_L-DELTA-L,THLF,EMPTY,TP24
GND_P2                   J19              3        DELTA_L-DELTA-L,THLF,EMPTY,TP24
GND_P2                   J23              3        DELTA_L-DELTA-L,THLF,EMPTY,TP24
GND_P2                   J26              3        DELTA_L-DELTA-L,THLF,EMPTY,TP24
GND_P2                   J29              3        DELTA_L-DELTA-L,THLF,EMPTY,TP24
H_CPU0_MEMTRIP_LVC1_N    U5               AB23     AST2600A1GP-AST2600A1-GP,SMLF,A
H_CPU0_MEMTRIP_LVC1_N    U25              N12      10M02SCU169C8G-10M02SCU169C8G,A
H_CPU0_PROCHOT_LVC1_N    R51              1        Q_RES_0402LF-0,5%,1/16W,CHIP,CA
H_CPU0_PROCHOT_LVC1_N    U5               D14      AST2600A1GP-AST2600A1-GP,SMLF,A
H_CPU0_PROCHOT_LVC1_R_N  R51              2        Q_RES_0402LF-0,5%,1/16W,CHIP,CA
H_CPU0_PROCHOT_LVC1_R_N  U25              J13      10M02SCU169C8G-10M02SCU169C8G,A
H_CPU1_MEMTRIP_LVC1_N    U5               AB24     AST2600A1GP-AST2600A1-GP,SMLF,A
H_CPU1_MEMTRIP_LVC1_N    U25              N10      10M02SCU169C8G-10M02SCU169C8G,A
H_CPU1_PROCHOT_LVC1_N    R177             1        Q_RES_0402LF-33       ,1%  ,1/A
H_CPU1_PROCHOT_LVC1_N    U5               P24      AST2600A1GP-AST2600A1-GP,SMLF,A
H_CPU1_PROCHOT_LVC1_R_N  R177             2        Q_RES_0402LF-33       ,1%  ,1/A
H_CPU1_PROCHOT_LVC1_R_N  U25              M2       10M02SCU169C8G-10M02SCU169C8G,A
I3C1_SCL_R               R184             2        Q_RES_0402LF-33       ,1%  ,1/A
I3C1_SCL_R               U5               AF23     AST2600A1GP-AST2600A1-GP,SMLF,A
I3C1_SDA_R               R185             2        Q_RES_0402LF-33       ,1%  ,1/A
I3C1_SDA_R               U5               AE24     AST2600A1GP-AST2600A1-GP,SMLF,A
I3C1_SPD_SCL             GF1              OA5      FCONN168_ME1016810106011-FCONNA
I3C1_SPD_SCL             R184             1        Q_RES_0402LF-33       ,1%  ,1/A
I3C1_SPD_SCL             R194             2        Q_RES_0402LF-4.7K,5%,1/16W,CHIA
I3C1_SPD_SDA             GF1              OA6      FCONN168_ME1016810106011-FCONNA
I3C1_SPD_SDA             R185             1        Q_RES_0402LF-33       ,1%  ,1/A
I3C1_SPD_SDA             R195             2        Q_RES_0402LF-4.7K,5%,1/16W,CHIA
I3C2_SCL_R               R186             2        Q_RES_0402LF-33       ,1%  ,1/A
I3C2_SCL_R               U5               AF22     AST2600A1GP-AST2600A1-GP,SMLF,A
I3C2_SDA_R               R187             2        Q_RES_0402LF-33       ,1%  ,1/A
I3C2_SDA_R               U5               AE22     AST2600A1GP-AST2600A1-GP,SMLF,A
I3C2_SPD_SCL             GF1              OA7      FCONN168_ME1016810106011-FCONNA
I3C2_SPD_SCL             R186             1        Q_RES_0402LF-33       ,1%  ,1/A
I3C2_SPD_SCL             R190             2        Q_RES_0402LF-4.7K,5%,1/16W,CHIA
I3C2_SPD_SDA             GF1              OA8      FCONN168_ME1016810106011-FCONNA
I3C2_SPD_SDA             R187             1        Q_RES_0402LF-33       ,1%  ,1/A
I3C2_SPD_SDA             R191             2        Q_RES_0402LF-4.7K,5%,1/16W,CHIA
I3C3_SCL_R               R198             1        Q_RES_0402LF-33       ,1%  ,1/A
I3C3_SCL_R               U5               AF25     AST2600A1GP-AST2600A1-GP,SMLF,A
I3C3_SDA_R               R199             1        Q_RES_0402LF-33       ,1%  ,1/A
I3C3_SDA_R               U5               AE26     AST2600A1GP-AST2600A1-GP,SMLF,A
I3C3_SPD_SCL             GF1              OA9      FCONN168_ME1016810106011-FCONNA
I3C3_SPD_SCL             R188             2        Q_RES_0402LF-4.7K,5%,1/16W,CHIA
I3C3_SPD_SCL             R198             2        Q_RES_0402LF-33       ,1%  ,1/A
I3C3_SPD_SDA             GF1              OA10     FCONN168_ME1016810106011-FCONNA
I3C3_SPD_SDA             R189             2        Q_RES_0402LF-4.7K,5%,1/16W,CHIA
I3C3_SPD_SDA             R199             2        Q_RES_0402LF-33       ,1%  ,1/A
I3C4_SCL_R               R200             1        Q_RES_0402LF-33       ,1%  ,1/A
I3C4_SCL_R               U5               AE25     AST2600A1GP-AST2600A1-GP,SMLF,A
I3C4_SDA_R               R201             1        Q_RES_0402LF-33       ,1%  ,1/A
I3C4_SDA_R               U5               AF24     AST2600A1GP-AST2600A1-GP,SMLF,A
I3C4_SPD_SCL             GF1              OA11     FCONN168_ME1016810106011-FCONNA
I3C4_SPD_SCL             R196             2        Q_RES_0402LF-4.7K,5%,1/16W,CHIA
I3C4_SPD_SCL             R200             2        Q_RES_0402LF-33       ,1%  ,1/A
I3C4_SPD_SDA             GF1              OA12     FCONN168_ME1016810106011-FCONNA
I3C4_SPD_SDA             R197             2        Q_RES_0402LF-4.7K,5%,1/16W,CHIA
I3C4_SPD_SDA             R201             2        Q_RES_0402LF-33       ,1%  ,1/A
IBMC_MIOZ                R127             2        Q_RES_0402LF-240,1%,1/16W,CHIPA
IBMC_MIOZ                U5               P5       AST2600A1GP-AST2600A1-GP,SMLF,A
ID_LED_BUF               Q12              3        MOSFET_DUAL_6P-2N7002KDW,SMLF,A
ID_LED_BUF               R813             1        Q_RES_0402LF-33       ,1%  ,1/A
ID_LED_BUF_R             C324             1        Q_CAP_0402-470PF,50V,10%,X7R,TA
ID_LED_BUF_R             D15              C        Q_LED_SMLF-LED_BLUE,12-215/BHCA
ID_LED_BUF_R             R813             2        Q_RES_0402LF-33       ,1%  ,1/A
ID_LED_BUF_R             R815             2        Q_RES_0402LF-10K,0.10%,1/16W,CA
ID_LED_P3V3_AUX          C197             1        Q_CAP_0402-0.1UF,25V,10%,X7R,CA
ID_LED_P3V3_AUX          D15              A        Q_LED_SMLF-LED_BLUE,12-215/BHCA
ID_LED_P3V3_AUX          R569             2        Q_RES_0402LF-1K,1%,1/16W,CHIP,A
ID_RST_BTN_BMC_N         R565             2        Q_RES_0402LF-0,5%,1/16W,CHIP,CA
ID_RST_BTN_BMC_N         U32              4        74LVC1G17GW-74LVC1G17GW,SMLF,IA
ID_RST_BTN_BMC_R_N       R565             1        Q_RES_0402LF-0,5%,1/16W,CHIP,CA
ID_RST_BTN_BMC_R_N       U5               AA23     AST2600A1GP-AST2600A1-GP,SMLF,A
IRQ_BMC_CPU_NMI          R166             2        Q_RES_0402LF-33       ,1%  ,1/A
IRQ_BMC_CPU_NMI          U5               J24      AST2600A1GP-AST2600A1-GP,SMLF,A
IRQ_BMC_CPU_NMI_R        R166             1        Q_RES_0402LF-33       ,1%  ,1/A
IRQ_BMC_CPU_NMI_R        U25              C2       10M02SCU169C8G-10M02SCU169C8G,A
IRQ_BMC_LPC_SERIRQ_ESPI_GF GF1              B3       FCONN168_ME1016810106011-FCONNA
IRQ_BMC_LPC_SERIRQ_ESPI_GF R116             2        Q_RES_0402LF-4.7K,5%,1/16W,CHIA
IRQ_BMC_LPC_SERIRQ_ESPI_GF R119             1        Q_RES_0402LF-33       ,1%  ,1/A
IRQ_BMC_PCH_NMI_N        R61              2        Q_RES_0402LF-4.7K,5%,1/16W,CHIA
IRQ_BMC_PCH_NMI_N        R571             1        Q_RES_0402LF-0,5%,1/16W,CHIP,CA
IRQ_BMC_PCH_NMI_N        U5               R23      AST2600A1GP-AST2600A1-GP,SMLF,A
IRQ_BMC_PCH_NMI_R_N      R571             2        Q_RES_0402LF-0,5%,1/16W,CHIP,CA
IRQ_BMC_PCH_NMI_R_N      U25              M1       10M02SCU169C8G-10M02SCU169C8G,A
IRQ_BMC_TPM_SPI_R_N      J10              9        SCONN11_9192031111LF-SCONN11_9A
IRQ_BMC_TPM_SPI_R_N      R113             2        Q_RES_0402LF-0,5%,1/16W,CHIP,CA
IRQ_CPU0_VRHOT_N         U5               V26      AST2600A1GP-AST2600A1-GP,SMLF,A
IRQ_CPU0_VRHOT_N         U25              N7       10M02SCU169C8G-10M02SCU169C8G,A
IRQ_CPU1_VRHOT_N         U5               U25      AST2600A1GP-AST2600A1-GP,SMLF,A
IRQ_CPU1_VRHOT_N         U25              M7       10M02SCU169C8G-10M02SCU169C8G,A
IRQ_ESPI_LPC_SERIRQ_ALERT0_N R119             2        Q_RES_0402LF-33       ,1%  ,1/A
IRQ_ESPI_LPC_SERIRQ_ALERT0_N U5               AD7      AST2600A1GP-AST2600A1-GP,SMLF,A
IRQ_OC_DETECT_EN_N       U5               V24      AST2600A1GP-AST2600A1-GP,SMLF,A
IRQ_OC_DETECT_EN_N       U25              M8       10M02SCU169C8G-10M02SCU169C8G,A
IRQ_OC_DETECT_N          U5               V25      AST2600A1GP-AST2600A1-GP,SMLF,A
IRQ_OC_DETECT_N          U25              N8       10M02SCU169C8G-10M02SCU169C8G,A
IRQ_PCH_SCI_WHEA_R_N     U5               A15      AST2600A1GP-AST2600A1-GP,SMLF,A
IRQ_PCH_SCI_WHEA_R_N     U25              M4       10M02SCU169C8G-10M02SCU169C8G,A
IRQ_SGPIO_BMC_N          R689             2        Q_RES_0402LF-33       ,1%  ,1/B
IRQ_SGPIO_BMC_N          U5               A24      AST2600A1GP-AST2600A1-GP,SMLF,A
IRQ_SGPIO_N              GF1              B40      FCONN168_ME1016810106011-FCONNA
IRQ_SGPIO_N              R68              2        Q_RES_0402LF-4.7K,5%,1/16W,CHIA
IRQ_SGPIO_N              R689             1        Q_RES_0402LF-33       ,1%  ,1/B
IRQ_SGPIO_N              R690             2        Q_RES_0402LF-33       ,1%  ,1/A
IRQ_SGPIO_R_N            R690             1        Q_RES_0402LF-33       ,1%  ,1/A
IRQ_SGPIO_R_N            U25              M12      10M02SCU169C8G-10M02SCU169C8G,A
IRQ_SMI_ACTIVE_BMC_N     R37              2        Q_RES_0402LF-33       ,1%  ,1/A
IRQ_SMI_ACTIVE_BMC_N     U5               AC9      AST2600A1GP-AST2600A1-GP,SMLF,A
IRQ_SMI_ACTIVE_GF_N      GF1              A56      FCONN168_ME1016810106011-FCONNA
IRQ_SMI_ACTIVE_GF_N      R37              1        Q_RES_0402LF-33       ,1%  ,1/A
IRQ_TPM_SPI_N            R59              2        Q_RES_0402LF-10K,1%,1/16W,CHIPA
IRQ_TPM_SPI_N            R113             1        Q_RES_0402LF-0,5%,1/16W,CHIP,CA
IRQ_TPM_SPI_N            R497             2        Q_RES_0402LF-10K,1%,1/16W,CHIPA
IRQ_TPM_SPI_N            R505             1        Q_RES_0402LF-0,5%,1/16W,CHIP,CA
IRQ_TPM_SPI_N            U5               AF15     AST2600A1GP-AST2600A1-GP,SMLF,A
IRQ_TPM_SPI_R_N          J5               9        SCONN11_9192031111LF-SCONN11_9A
IRQ_TPM_SPI_R_N          R505             2        Q_RES_0402LF-0,5%,1/16W,CHIP,CA
IRQ_UV_DETECT_N          U5               U24      AST2600A1GP-AST2600A1-GP,SMLF,A
IRQ_UV_DETECT_N          U25              H2       10M02SCU169C8G-10M02SCU169C8G,A
JTAG_1_BMC_TCK_R         R222             1        Q_RES_0402LF-33       ,1%  ,1/A
JTAG_1_BMC_TCK_R         U5               E17      AST2600A1GP-AST2600A1-GP,SMLF,A
JTAG_1_BMC_TDI_R         R639             1        Q_RES_0402LF-33       ,1%  ,1/A
JTAG_1_BMC_TDI_R         U5               A16      AST2600A1GP-AST2600A1-GP,SMLF,A
JTAG_1_BMC_TDO_R         R224             1        Q_RES_0402LF-33       ,1%  ,1/A
JTAG_1_BMC_TDO_R         U5               C16      AST2600A1GP-AST2600A1-GP,SMLF,A
JTAG_1_BMC_TMS_R         R223             1        Q_RES_0402LF-33       ,1%  ,1/A
JTAG_1_BMC_TMS_R         U5               D16      AST2600A1GP-AST2600A1-GP,SMLF,A
JTAG_1_BMC_TRST_R        R221             1        Q_RES_0402LF-33       ,1%  ,1/A
JTAG_1_BMC_TRST_R        U5               D17      AST2600A1GP-AST2600A1-GP,SMLF,A
JTAG_MB_TCK              GF1              A34      FCONN168_ME1016810106011-FCONNA
JTAG_MB_TCK              R222             2        Q_RES_0402LF-33       ,1%  ,1/A
JTAG_MB_TCK              R228             2        Q_RES_0402LF-10K,0.10%,1/16W,CA
JTAG_MB_TDI              GF1              A36      FCONN168_ME1016810106011-FCONNA
JTAG_MB_TDI              R226             2        Q_RES_0402LF-10K,0.10%,1/16W,CA
JTAG_MB_TDI              R639             2        Q_RES_0402LF-33       ,1%  ,1/A
JTAG_MB_TDO              GF1              A37      FCONN168_ME1016810106011-FCONNA
JTAG_MB_TDO              R224             2        Q_RES_0402LF-33       ,1%  ,1/A
JTAG_MB_TDO              R230             2        Q_RES_0402LF-10K,0.10%,1/16W,CA
JTAG_MB_TMS              GF1              A35      FCONN168_ME1016810106011-FCONNA
JTAG_MB_TMS              R223             2        Q_RES_0402LF-33       ,1%  ,1/A
JTAG_MB_TMS              R227             2        Q_RES_0402LF-10K,0.10%,1/16W,CA
JTAG_MB_TRST_N           R221             2        Q_RES_0402LF-33       ,1%  ,1/A
JTAG_MB_TRST_N           R229             2        Q_RES_0402LF-4.7K,1%,1/16W,EMPA
JTAG_SCM_CONN_TCK        J7               2        CONN7_4400547-CONN7_440054-7,TA
JTAG_SCM_CONN_TCK        R514             2        Q_RES_0402LF-33       ,1%  ,1/A
JTAG_SCM_CONN_TDI        J7               5        CONN7_4400547-CONN7_440054-7,TA
JTAG_SCM_CONN_TDI        R516             2        Q_RES_0402LF-33       ,1%  ,1/A
JTAG_SCM_CONN_TDO        J7               3        CONN7_4400547-CONN7_440054-7,TA
JTAG_SCM_CONN_TDO        R517             2        Q_RES_0402LF-33       ,1%  ,1/A
JTAG_SCM_CONN_TMS        J7               4        CONN7_4400547-CONN7_440054-7,TA
JTAG_SCM_CONN_TMS        R515             2        Q_RES_0402LF-33       ,1%  ,1/A
JTAG_SCM_NTRST           R206             2        Q_RES_0402LF-47K,5%,1/16W,EMPTA
JTAG_SCM_NTRST           U5               F11      AST2600A1GP-AST2600A1-GP,SMLF,A
JTAG_SCM_PLD_JTAGEN      R509             2        Q_RES_0402LF-33       ,1%  ,1/A
JTAG_SCM_PLD_JTAGEN      R518             2        Q_RES_0402LF-33       ,1%  ,1/A
JTAG_SCM_PLD_JTAGEN      U25              E5       10M02SCU169C8G-10M02SCU169C8G,A
JTAG_SCM_PLD_R1_JTAGEN   J7               6        CONN7_4400547-CONN7_440054-7,TA
JTAG_SCM_PLD_R1_JTAGEN   R518             1        Q_RES_0402LF-33       ,1%  ,1/A
JTAG_SCM_PLD_TCK         R510             2        Q_RES_0402LF-33       ,1%  ,1/A
JTAG_SCM_PLD_TCK         R514             1        Q_RES_0402LF-33       ,1%  ,1/A
JTAG_SCM_PLD_TCK         U25              G2       10M02SCU169C8G-10M02SCU169C8G,A
JTAG_SCM_PLD_TDI         R512             2        Q_RES_0402LF-33       ,1%  ,1/A
JTAG_SCM_PLD_TDI         R516             1        Q_RES_0402LF-33       ,1%  ,1/A
JTAG_SCM_PLD_TDI         U25              F5       10M02SCU169C8G-10M02SCU169C8G,A
JTAG_SCM_PLD_TDO         R513             2        Q_RES_0402LF-33       ,1%  ,1/A
JTAG_SCM_PLD_TDO         R517             1        Q_RES_0402LF-33       ,1%  ,1/A
JTAG_SCM_PLD_TDO         U25              F6       10M02SCU169C8G-10M02SCU169C8G,A
JTAG_SCM_PLD_TMS         R511             2        Q_RES_0402LF-33       ,1%  ,1/A
JTAG_SCM_PLD_TMS         R515             1        Q_RES_0402LF-33       ,1%  ,1/A
JTAG_SCM_PLD_TMS         U25              G1       10M02SCU169C8G-10M02SCU169C8G,A
JTAG_SCM_TCK             R202             2        Q_RES_0402LF-10K,0.10%,1/16W,CA
JTAG_SCM_TCK             R510             1        Q_RES_0402LF-33       ,1%  ,1/A
JTAG_SCM_TCK             U5               B9       AST2600A1GP-AST2600A1-GP,SMLF,A
JTAG_SCM_TDI             R204             2        Q_RES_0402LF-10K,0.10%,1/16W,CA
JTAG_SCM_TDI             R512             1        Q_RES_0402LF-33       ,1%  ,1/A
JTAG_SCM_TDI             U5               D9       AST2600A1GP-AST2600A1-GP,SMLF,A
JTAG_SCM_TDO             R513             1        Q_RES_0402LF-33       ,1%  ,1/A
JTAG_SCM_TDO             R523             2        Q_RES_0402LF-10K,0.10%,1/16W,CA
JTAG_SCM_TDO             U5               C9       AST2600A1GP-AST2600A1-GP,SMLF,A
JTAG_SCM_TMS             R203             2        Q_RES_0402LF-10K,0.10%,1/16W,CA
JTAG_SCM_TMS             R511             1        Q_RES_0402LF-33       ,1%  ,1/A
JTAG_SCM_TMS             U5               A9       AST2600A1GP-AST2600A1-GP,SMLF,A
LED1_AD1_100M            J1               L2       SCONN14_RS6QU0001-SCONN14_RS6-A
LED1_AD1_100M            R305             2        Q_RES_0402LF-220,5%,1/16W,CHIPA
LED2_RXDELAY_1G          J1               L1       SCONN14_RS6QU0001-SCONN14_RS6-A
LED2_RXDELAY_1G          R306             2        Q_RES_0402LF-220,5%,1/16W,CHIPA
LED3_AD0_ACT             J1               L3       SCONN14_RS6QU0001-SCONN14_RS6-A
LED3_AD0_ACT             R304             2        Q_RES_0402LF-220,5%,1/16W,CHIPA
LED_POSTCODE_0_N         D0               C        Q_LED_SMLF-LED_GREEN,19-213/GVA
LED_POSTCODE_0_N         U5               P25      AST2600A1GP-AST2600A1-GP,SMLF,A
LED_POSTCODE_1_N         D1               C        Q_LED_SMLF-LED_GREEN,19-213/GVA
LED_POSTCODE_1_N         U5               N23      AST2600A1GP-AST2600A1-GP,SMLF,A
LED_POSTCODE_2_N         D2               C        Q_LED_SMLF-LED_GREEN,19-213/GVA
LED_POSTCODE_2_N         U5               N25      AST2600A1GP-AST2600A1-GP,SMLF,A
LED_POSTCODE_3_N         D3               C        Q_LED_SMLF-LED_GREEN,19-213/GVA
LED_POSTCODE_3_N         U5               N24      AST2600A1GP-AST2600A1-GP,SMLF,A
LED_POSTCODE_4_N         D4               C        Q_LED_SMLF-LED_RED,19-217/R6C-A
LED_POSTCODE_4_N         U5               P26      AST2600A1GP-AST2600A1-GP,SMLF,A
LED_POSTCODE_5_N         D5               C        Q_LED_SMLF-LED_RED,19-217/R6C-A
LED_POSTCODE_5_N         U5               M23      AST2600A1GP-AST2600A1-GP,SMLF,A
LED_POSTCODE_6_N         D6               C        Q_LED_SMLF-LED_RED,19-217/R6C-A
LED_POSTCODE_6_N         U5               N26      AST2600A1GP-AST2600A1-GP,SMLF,A
LED_POSTCODE_7_N         D7               C        Q_LED_SMLF-LED_RED,19-217/R6C-A
LED_POSTCODE_7_N         U5               M26      AST2600A1GP-AST2600A1-GP,SMLF,A
LOADSW_CT                C181             1        Q_CAP_0402-1UF,16V,10%,EMPTY,TA
LOADSW_CT                U15              6        TPS22965DSGR-TPS22965DSGR,SMLFA
LOADSW_VBIAS             R387             2        Q_RES_0402LF-4.7K,1%,1/16W,CHIA
LOADSW_VBIAS             R388             1        Q_RES_0402LF-4.7K,1%,1/16W,EMPA
LOADSW_VBIAS             U15              4        TPS22965DSGR-TPS22965DSGR,SMLFA
LPC_ESPI_SEL             GF1              B9       FCONN168_ME1016810106011-FCONNA
LPC_ESPI_SEL             R41              2        Q_RES_0402LF-10K,1%,1/16W,CHIPA
LPC_ESPI_SEL             R713             2        Q_RES_0402LF-33       ,1%  ,1/A
LPC_ESPI_SEL             R714             1        Q_RES_0402LF-2K,1%,1/16W,CHIP,A
LPC_ESPI_SEL_LV5         C268             1        Q_CAP_0402-1UF,16V,10%,EMPTY,TA
LPC_ESPI_SEL_LV5         Q8               2        MOSFET_DUAL_6P-DMN2400UV-7,SMLA
LPC_ESPI_SEL_LV5         Q9               D        MOSFET_N_GSD-DMG6968U-7,SMLF,IA
LPC_ESPI_SEL_LV5         R715             2        Q_RES_0402LF-10K,1%,1/16W,CHIPA
LPC_ESPI_SEL_N           C270             1        Q_CAP_0402-1UF,16V,10%,EMPTY,TA
LPC_ESPI_SEL_N           Q8               5        MOSFET_DUAL_6P-DMN2400UV-7,SMLA
LPC_ESPI_SEL_N           Q9               G        MOSFET_N_GSD-DMG6968U-7,SMLF,IA
LPC_ESPI_SEL_N           Q10              D        MOSFET_N_GSD-DMG6968U-7,SMLF,IA
LPC_ESPI_SEL_N           R716             2        Q_RES_0402LF-10K,1%,1/16W,CHIPA
LPC_ESPI_SEL_R           C273             1        Q_CAP_0402-1UF,16V,10%,EMPTY,TA
LPC_ESPI_SEL_R           Q10              G        MOSFET_N_GSD-DMG6968U-7,SMLF,IA
LPC_ESPI_SEL_R           R713             1        Q_RES_0402LF-33       ,1%  ,1/A
LPC_ESPI_SEL_R1          C267             1        Q_CAP_0402-1UF,16V,10%,EMPTY,TA
LPC_ESPI_SEL_R1          Q7               1        MOSFET_N_123-BSS123-7-F,SMLF,IA
LPC_ESPI_SEL_R1          R714             2        Q_RES_0402LF-2K,1%,1/16W,CHIP,A
MB_JTAG_PLD_R_JTAGEN     R508             2        Q_RES_0402LF-10K,1%,1/16W,CHIPA
MB_JTAG_PLD_R_JTAGEN     R509             1        Q_RES_0402LF-33       ,1%  ,1/A
MB_JTAG_PLD_R_JTAGEN     SW3              4        SW4S_DHNF02FTVTR-SW4S_DHNF-02FA
M_BMC_DDR4_ALERT_N       R9               1        Q_RES_0402LF-4.7K,5%,1/16W,CHIA
M_BMC_DDR4_ALERT_N       U1               P9       K4A8G165WCBCTD-K4A8G165WC-BCTDA
M_BMC_DDR4_ALERT_N       U5               N4       AST2600A1GP-AST2600A1-GP,SMLF,A
M_BMC_DDR4_BG1           R1               1        Q_RES_0402LF-0,5%,1/16W,EMPTY,A
M_BMC_DDR4_BG1           R2               1        Q_RES_0402LF-0,5%,1/16W,CHIP,CA
M_BMC_DDR4_BG1           U1               M9       K4A8G165WCBCTD-K4A8G165WC-BCTDA
M_BMC_DDR4_DQ<0>         U1               G2       K4A8G165WCBCTD-K4A8G165WC-BCTDA
M_BMC_DDR4_DQ<0>         U5               T3       AST2600A1GP-AST2600A1-GP,SMLF,A
M_BMC_DDR4_DQ<1>         U1               F7       K4A8G165WCBCTD-K4A8G165WC-BCTDA
M_BMC_DDR4_DQ<1>         U5               R4       AST2600A1GP-AST2600A1-GP,SMLF,A
M_BMC_DDR4_DQ<2>         U1               H3       K4A8G165WCBCTD-K4A8G165WC-BCTDA
M_BMC_DDR4_DQ<2>         U5               U1       AST2600A1GP-AST2600A1-GP,SMLF,A
M_BMC_DDR4_DQ<3>         U1               H7       K4A8G165WCBCTD-K4A8G165WC-BCTDA
M_BMC_DDR4_DQ<3>         U5               R3       AST2600A1GP-AST2600A1-GP,SMLF,A
M_BMC_DDR4_DQ<4>         U1               H2       K4A8G165WCBCTD-K4A8G165WC-BCTDA
M_BMC_DDR4_DQ<4>         U5               R1       AST2600A1GP-AST2600A1-GP,SMLF,A
M_BMC_DDR4_DQ<5>         U1               H8       K4A8G165WCBCTD-K4A8G165WC-BCTDA
M_BMC_DDR4_DQ<5>         U5               P1       AST2600A1GP-AST2600A1-GP,SMLF,A
M_BMC_DDR4_DQ<6>         U1               J3       K4A8G165WCBCTD-K4A8G165WC-BCTDA
M_BMC_DDR4_DQ<6>         U5               P2       AST2600A1GP-AST2600A1-GP,SMLF,A
M_BMC_DDR4_DQ<7>         U1               J7       K4A8G165WCBCTD-K4A8G165WC-BCTDA
M_BMC_DDR4_DQ<7>         U5               P3       AST2600A1GP-AST2600A1-GP,SMLF,A
M_BMC_DDR4_DQ<8>         U1               A3       K4A8G165WCBCTD-K4A8G165WC-BCTDA
M_BMC_DDR4_DQ<8>         U5               W2       AST2600A1GP-AST2600A1-GP,SMLF,A
M_BMC_DDR4_DQ<9>         U1               B8       K4A8G165WCBCTD-K4A8G165WC-BCTDA
M_BMC_DDR4_DQ<9>         U5               V3       AST2600A1GP-AST2600A1-GP,SMLF,A
M_BMC_DDR4_DQ<10>        U1               C3       K4A8G165WCBCTD-K4A8G165WC-BCTDA
M_BMC_DDR4_DQ<10>        U5               W1       AST2600A1GP-AST2600A1-GP,SMLF,A
M_BMC_DDR4_DQ<11>        U1               C7       K4A8G165WCBCTD-K4A8G165WC-BCTDA
M_BMC_DDR4_DQ<11>        U5               W3       AST2600A1GP-AST2600A1-GP,SMLF,A
M_BMC_DDR4_DQ<12>        U1               C2       K4A8G165WCBCTD-K4A8G165WC-BCTDA
M_BMC_DDR4_DQ<12>        U5               W4       AST2600A1GP-AST2600A1-GP,SMLF,A
M_BMC_DDR4_DQ<13>        U1               C8       K4A8G165WCBCTD-K4A8G165WC-BCTDA
M_BMC_DDR4_DQ<13>        U5               U4       AST2600A1GP-AST2600A1-GP,SMLF,A
M_BMC_DDR4_DQ<14>        U1               D3       K4A8G165WCBCTD-K4A8G165WC-BCTDA
M_BMC_DDR4_DQ<14>        U5               V4       AST2600A1GP-AST2600A1-GP,SMLF,A
M_BMC_DDR4_DQ<15>        U1               D7       K4A8G165WCBCTD-K4A8G165WC-BCTDA
M_BMC_DDR4_DQ<15>        U5               U3       AST2600A1GP-AST2600A1-GP,SMLF,A
M_BMC_DDR4_DQS0_N        U1               F3       K4A8G165WCBCTD-K4A8G165WC-BCTDA
M_BMC_DDR4_DQS0_N        U5               T1       AST2600A1GP-AST2600A1-GP,SMLF,A
M_BMC_DDR4_DQS0_P        U1               G3       K4A8G165WCBCTD-K4A8G165WC-BCTDA
M_BMC_DDR4_DQS0_P        U5               T2       AST2600A1GP-AST2600A1-GP,SMLF,A
M_BMC_DDR4_DQS1_N        U1               A7       K4A8G165WCBCTD-K4A8G165WC-BCTDA
M_BMC_DDR4_DQS1_N        U5               V1       AST2600A1GP-AST2600A1-GP,SMLF,A
M_BMC_DDR4_DQS1_P        U1               B7       K4A8G165WCBCTD-K4A8G165WC-BCTDA
M_BMC_DDR4_DQS1_P        U5               V2       AST2600A1GP-AST2600A1-GP,SMLF,A
M_BMC_DDR4_MA<0>         R326             2        Q_RES_0402LF-120,1%,1/16W,CHIPA
M_BMC_DDR4_MA<0>         R351             1        Q_RES_0402LF-120,1%,1/16W,CHIPA
M_BMC_DDR4_MA<0>         U1               P3       K4A8G165WCBCTD-K4A8G165WC-BCTDA
M_BMC_DDR4_MA<0>         U5               F3       AST2600A1GP-AST2600A1-GP,SMLF,A
M_BMC_DDR4_MA<1>         R327             2        Q_RES_0402LF-120,1%,1/16W,CHIPA
M_BMC_DDR4_MA<1>         R352             1        Q_RES_0402LF-120,1%,1/16W,CHIPA
M_BMC_DDR4_MA<1>         U1               P7       K4A8G165WCBCTD-K4A8G165WC-BCTDA
M_BMC_DDR4_MA<1>         U5               K5       AST2600A1GP-AST2600A1-GP,SMLF,A
M_BMC_DDR4_MA<2>         R328             2        Q_RES_0402LF-120,1%,1/16W,CHIPA
M_BMC_DDR4_MA<2>         R353             1        Q_RES_0402LF-120,1%,1/16W,CHIPA
M_BMC_DDR4_MA<2>         U1               R3       K4A8G165WCBCTD-K4A8G165WC-BCTDA
M_BMC_DDR4_MA<2>         U5               F1       AST2600A1GP-AST2600A1-GP,SMLF,A
M_BMC_DDR4_MA<3>         R329             2        Q_RES_0402LF-120,1%,1/16W,CHIPA
M_BMC_DDR4_MA<3>         R354             1        Q_RES_0402LF-120,1%,1/16W,CHIPA
M_BMC_DDR4_MA<3>         U1               N7       K4A8G165WCBCTD-K4A8G165WC-BCTDA
M_BMC_DDR4_MA<3>         U5               H3       AST2600A1GP-AST2600A1-GP,SMLF,A
M_BMC_DDR4_MA<4>         R330             2        Q_RES_0402LF-120,1%,1/16W,CHIPA
M_BMC_DDR4_MA<4>         R355             1        Q_RES_0402LF-120,1%,1/16W,CHIPA
M_BMC_DDR4_MA<4>         U1               N3       K4A8G165WCBCTD-K4A8G165WC-BCTDA
M_BMC_DDR4_MA<4>         U5               J3       AST2600A1GP-AST2600A1-GP,SMLF,A
M_BMC_DDR4_MA<5>         R331             2        Q_RES_0402LF-120,1%,1/16W,CHIPA
M_BMC_DDR4_MA<5>         R356             1        Q_RES_0402LF-120,1%,1/16W,CHIPA
M_BMC_DDR4_MA<5>         U1               P8       K4A8G165WCBCTD-K4A8G165WC-BCTDA
M_BMC_DDR4_MA<5>         U5               L1       AST2600A1GP-AST2600A1-GP,SMLF,A
M_BMC_DDR4_MA<6>         R332             2        Q_RES_0402LF-120,1%,1/16W,CHIPA
M_BMC_DDR4_MA<6>         R357             1        Q_RES_0402LF-120,1%,1/16W,CHIPA
M_BMC_DDR4_MA<6>         U1               P2       K4A8G165WCBCTD-K4A8G165WC-BCTDA
M_BMC_DDR4_MA<6>         U5               M5       AST2600A1GP-AST2600A1-GP,SMLF,A
M_BMC_DDR4_MA<7>         R333             2        Q_RES_0402LF-120,1%,1/16W,CHIPA
M_BMC_DDR4_MA<7>         R358             1        Q_RES_0402LF-120,1%,1/16W,CHIPA
M_BMC_DDR4_MA<7>         U1               R8       K4A8G165WCBCTD-K4A8G165WC-BCTDA
M_BMC_DDR4_MA<7>         U5               M2       AST2600A1GP-AST2600A1-GP,SMLF,A
M_BMC_DDR4_MA<8>         R334             2        Q_RES_0402LF-120,1%,1/16W,CHIPA
M_BMC_DDR4_MA<8>         R359             1        Q_RES_0402LF-120,1%,1/16W,CHIPA
M_BMC_DDR4_MA<8>         U1               R2       K4A8G165WCBCTD-K4A8G165WC-BCTDA
M_BMC_DDR4_MA<8>         U5               M1       AST2600A1GP-AST2600A1-GP,SMLF,A
M_BMC_DDR4_MA<9>         R335             2        Q_RES_0402LF-120,1%,1/16W,CHIPA
M_BMC_DDR4_MA<9>         R360             1        Q_RES_0402LF-120,1%,1/16W,CHIPA
M_BMC_DDR4_MA<9>         U1               R7       K4A8G165WCBCTD-K4A8G165WC-BCTDA
M_BMC_DDR4_MA<9>         U5               N1       AST2600A1GP-AST2600A1-GP,SMLF,A
M_BMC_DDR4_MA<10>        R336             2        Q_RES_0402LF-120,1%,1/16W,CHIPA
M_BMC_DDR4_MA<10>        R361             1        Q_RES_0402LF-120,1%,1/16W,CHIPA
M_BMC_DDR4_MA<10>        U1               M3       K4A8G165WCBCTD-K4A8G165WC-BCTDA
M_BMC_DDR4_MA<10>        U5               F2       AST2600A1GP-AST2600A1-GP,SMLF,A
M_BMC_DDR4_MA<11>        R337             2        Q_RES_0402LF-120,1%,1/16W,CHIPA
M_BMC_DDR4_MA<11>        R362             1        Q_RES_0402LF-120,1%,1/16W,CHIPA
M_BMC_DDR4_MA<11>        U1               T2       K4A8G165WCBCTD-K4A8G165WC-BCTDA
M_BMC_DDR4_MA<11>        U5               G1       AST2600A1GP-AST2600A1-GP,SMLF,A
M_BMC_DDR4_MA<12>        R338             2        Q_RES_0402LF-120,1%,1/16W,CHIPA
M_BMC_DDR4_MA<12>        R363             1        Q_RES_0402LF-120,1%,1/16W,CHIPA
M_BMC_DDR4_MA<12>        U1               M7       K4A8G165WCBCTD-K4A8G165WC-BCTDA
M_BMC_DDR4_MA<12>        U5               L4       AST2600A1GP-AST2600A1-GP,SMLF,A
M_BMC_DDR4_MA<13>        R339             2        Q_RES_0402LF-120,1%,1/16W,CHIPA
M_BMC_DDR4_MA<13>        R364             1        Q_RES_0402LF-120,1%,1/16W,CHIPA
M_BMC_DDR4_MA<13>        U1               T8       K4A8G165WCBCTD-K4A8G165WC-BCTDA
M_BMC_DDR4_MA<13>        U5               K3       AST2600A1GP-AST2600A1-GP,SMLF,A
M_BMC_DDR4_MACT_N        R344             2        Q_RES_0402LF-120,1%,1/16W,CHIPA
M_BMC_DDR4_MACT_N        R369             1        Q_RES_0402LF-120,1%,1/16W,CHIPA
M_BMC_DDR4_MACT_N        U1               L3       K4A8G165WCBCTD-K4A8G165WC-BCTDA
M_BMC_DDR4_MACT_N        U5               H1       AST2600A1GP-AST2600A1-GP,SMLF,A
M_BMC_DDR4_MBA0          R346             2        Q_RES_0402LF-120,1%,1/16W,CHIPA
M_BMC_DDR4_MBA0          R371             1        Q_RES_0402LF-120,1%,1/16W,CHIPA
M_BMC_DDR4_MBA0          U1               N2       K4A8G165WCBCTD-K4A8G165WC-BCTDA
M_BMC_DDR4_MBA0          U5               G4       AST2600A1GP-AST2600A1-GP,SMLF,A
M_BMC_DDR4_MBA1          R347             2        Q_RES_0402LF-120,1%,1/16W,CHIPA
M_BMC_DDR4_MBA1          R372             1        Q_RES_0402LF-120,1%,1/16W,CHIPA
M_BMC_DDR4_MBA1          U1               N8       K4A8G165WCBCTD-K4A8G165WC-BCTDA
M_BMC_DDR4_MBA1          U5               H5       AST2600A1GP-AST2600A1-GP,SMLF,A
M_BMC_DDR4_MBG0          R345             2        Q_RES_0402LF-120,1%,1/16W,CHIPA
M_BMC_DDR4_MBG0          R370             1        Q_RES_0402LF-120,1%,1/16W,CHIPA
M_BMC_DDR4_MBG0          U1               M2       K4A8G165WCBCTD-K4A8G165WC-BCTDA
M_BMC_DDR4_MBG0          U5               G3       AST2600A1GP-AST2600A1-GP,SMLF,A
M_BMC_DDR4_MBG1          R1               2        Q_RES_0402LF-0,5%,1/16W,EMPTY,A
M_BMC_DDR4_MBG1          R350             2        Q_RES_0402LF-120,1%,1/16W,EMPTA
M_BMC_DDR4_MBG1          R375             1        Q_RES_0402LF-120,1%,1/16W,EMPTA
M_BMC_DDR4_MBG1          U5               M3       AST2600A1GP-AST2600A1-GP,SMLF,A
M_BMC_DDR4_MCAS_N        R341             2        Q_RES_0402LF-120,1%,1/16W,CHIPA
M_BMC_DDR4_MCAS_N        R366             1        Q_RES_0402LF-120,1%,1/16W,CHIPA
M_BMC_DDR4_MCAS_N        U1               M8       K4A8G165WCBCTD-K4A8G165WC-BCTDA
M_BMC_DDR4_MCAS_N        U5               J4       AST2600A1GP-AST2600A1-GP,SMLF,A
M_BMC_DDR4_MCKE          R349             2        Q_RES_0402LF-120,1%,1/16W,CHIPA
M_BMC_DDR4_MCKE          R374             1        Q_RES_0402LF-120,1%,1/16W,CHIPA
M_BMC_DDR4_MCKE          U1               K2       K4A8G165WCBCTD-K4A8G165WC-BCTDA
M_BMC_DDR4_MCKE          U5               L5       AST2600A1GP-AST2600A1-GP,SMLF,A
M_BMC_DDR4_MCLK_C        C12              1        Q_CAP_0402-0.22UF,16V,10%,X7R,A
M_BMC_DDR4_MCLK_C        C229             1        Q_CAP_0402-0.22UF,16V,10%,EMPTA
M_BMC_DDR4_MCLK_C        R7               2        Q_RES_0402LF-60.4,1%,1/16W,CHIA
M_BMC_DDR4_MCLK_C        R8               2        Q_RES_0402LF-60.4,1%,1/16W,CHIA
M_BMC_DDR4_MCLK_DN       R7               1        Q_RES_0402LF-60.4,1%,1/16W,CHIA
M_BMC_DDR4_MCLK_DN       U1               K8       K4A8G165WCBCTD-K4A8G165WC-BCTDA
M_BMC_DDR4_MCLK_DN       U5               K1       AST2600A1GP-AST2600A1-GP,SMLF,A
M_BMC_DDR4_MCLK_DP       R8               1        Q_RES_0402LF-60.4,1%,1/16W,CHIA
M_BMC_DDR4_MCLK_DP       U1               K7       K4A8G165WCBCTD-K4A8G165WC-BCTDA
M_BMC_DDR4_MCLK_DP       U5               K2       AST2600A1GP-AST2600A1-GP,SMLF,A
M_BMC_DDR4_MCS_N         R343             2        Q_RES_0402LF-120,1%,1/16W,CHIPA
M_BMC_DDR4_MCS_N         R368             1        Q_RES_0402LF-120,1%,1/16W,CHIPA
M_BMC_DDR4_MCS_N         U1               L7       K4A8G165WCBCTD-K4A8G165WC-BCTDA
M_BMC_DDR4_MCS_N         U5               H2       AST2600A1GP-AST2600A1-GP,SMLF,A
M_BMC_DDR4_MDM0          U1               E7       K4A8G165WCBCTD-K4A8G165WC-BCTDA
M_BMC_DDR4_MDM0          U5               N3       AST2600A1GP-AST2600A1-GP,SMLF,A
M_BMC_DDR4_MDM1          U1               E2       K4A8G165WCBCTD-K4A8G165WC-BCTDA
M_BMC_DDR4_MDM1          U5               R5       AST2600A1GP-AST2600A1-GP,SMLF,A
M_BMC_DDR4_MODT          R348             2        Q_RES_0402LF-120,1%,1/16W,CHIPA
M_BMC_DDR4_MODT          R373             1        Q_RES_0402LF-120,1%,1/16W,CHIPA
M_BMC_DDR4_MODT          U1               K3       K4A8G165WCBCTD-K4A8G165WC-BCTDA
M_BMC_DDR4_MODT          U5               J1       AST2600A1GP-AST2600A1-GP,SMLF,A
M_BMC_DDR4_MRAS_N        R342             2        Q_RES_0402LF-120,1%,1/16W,CHIPA
M_BMC_DDR4_MRAS_N        R367             1        Q_RES_0402LF-120,1%,1/16W,CHIPA
M_BMC_DDR4_MRAS_N        U1               L8       K4A8G165WCBCTD-K4A8G165WC-BCTDA
M_BMC_DDR4_MRAS_N        U5               J5       AST2600A1GP-AST2600A1-GP,SMLF,A
M_BMC_DDR4_MWE_N         R340             2        Q_RES_0402LF-120,1%,1/16W,CHIPA
M_BMC_DDR4_MWE_N         R365             1        Q_RES_0402LF-120,1%,1/16W,CHIPA
M_BMC_DDR4_MWE_N         U1               L2       K4A8G165WCBCTD-K4A8G165WC-BCTDA
M_BMC_DDR4_MWE_N         U5               G5       AST2600A1GP-AST2600A1-GP,SMLF,A
M_BMC_DDR4_RST_N         U1               P1       K4A8G165WCBCTD-K4A8G165WC-BCTDA
M_BMC_DDR4_RST_N         U5               L3       AST2600A1GP-AST2600A1-GP,SMLF,A
M_BMC_DDR4_ZQU           R3               1        Q_RES_0402LF-0,5%,1/16W,CHIP,CA
M_BMC_DDR4_ZQU           U1               E9       K4A8G165WCBCTD-K4A8G165WC-BCTDA
P0V6_DDR_VREF_AUX        C10              1        Q_CAP_0402-0.1UF,25V,10%,X7R,CA
P0V6_DDR_VREF_AUX        C21              1        Q_CAP_C0402-0.01UF,50V,10%,EMPA
P0V6_DDR_VREF_AUX        C22              1        Q_CAP_0402-0.1UF,25V,10%,EMPTYA
P0V6_DDR_VREF_AUX        C23              1        Q_CAP_0402-0.1UF,25V,10%,X7R,CA
P0V6_DDR_VREF_AUX        C168             1        Q_CAP_0402-0.1UF,25V,10%,X7R,CA
P0V6_DDR_VREF_AUX        C169             2        Q_CAP_C0402-0.01UF,50V,10%,EMPA
P0V6_DDR_VREF_AUX        C170             1        Q_CAP_C0402-0.01UF,50V,10%,X7RA
P0V6_DDR_VREF_AUX        R324             2        Q_RES_0402LF-1K,1%,1/16W,CHIP,A
P0V6_DDR_VREF_AUX        R325             1        Q_RES_0402LF-1K,1%,1/16W,CHIP,A
P0V6_DDR_VREF_AUX        U1               M1       K4A8G165WCBCTD-K4A8G165WC-BCTDA
P0V6_DDR_VREF_AUX        U5               T5       AST2600A1GP-AST2600A1-GP,SMLF,A
P0V6_DDR_VREF_AUX        U5               U5       AST2600A1GP-AST2600A1-GP,SMLF,A
P12V_AUX                 C329             1        Q_CAP_C0805-22UF,25V,20%,X5R,CA
P12V_AUX                 C330             1        Q_CAP_C0805-22UF,25V,20%,X5R,CA
P12V_AUX                 GF1              OA1      FCONN168_ME1016810106011-FCONNA
P12V_AUX                 GF1              OA2      FCONN168_ME1016810106011-FCONNA
P12V_AUX                 GF1              OB1      FCONN168_ME1016810106011-FCONNA
P12V_AUX                 GF1              OB2      FCONN168_ME1016810106011-FCONNA
P12V_AUX                 PL4              1        Q_INDUCTOR_SMLF-BLM18SN220TN1DA
P12V_AUX                 PL19             1        Q_INDUCTOR_SMLF-BLM18SN220TN1DA
P12V_AUX                 PL29             1        Q_INDUCTOR_SMLF-BLM18SN220TN1DA
P12V_AUX                 PL32             1        Q_INDUCTOR_SMLF-BLM18SN220TN1DA
P12V_AUX                 PR521            1        Q_RES_0402LF-681K,1%,1/16W,CHIA
P12V_AUX                 R785             1        Q_RES_0402LF-15.8K,1%,1/16W,CHA
P12V_SENSOR              C290             1        Q_CAP_0402-0.1UF,25V,10%,X7R,CA
P12V_SENSOR              R785             2        Q_RES_0402LF-15.8K,1%,1/16W,CHA
P12V_SENSOR              R786             1        Q_RES_0402LF-2K,1%,1/16W,CHIP,A
P12V_SENSOR              U5               AD20     AST2600A1GP-AST2600A1-GP,SMLF,A
P1V0_AUX                 C86              1        Q_CAP_0402-0.1UF,25V,10%,X7R,CA
P1V0_AUX                 C92              1        Q_CAP_0402-0.1UF,25V,10%,X7R,CA
P1V0_AUX                 C99              1        Q_CAP_0402-0.1UF,25V,10%,X7R,CA
P1V0_AUX                 C104             1        Q_CAP_C0402-1UF,25V,10%,X6S,CHA
P1V0_AUX                 C108             1        Q_CAP_C0402-1UF,25V,10%,X6S,CHA
P1V0_AUX                 C113             1        Q_CAP_C0603-22UF,10V,20%,X5R,CA
P1V0_AUX                 C118             1        Q_CAP_C0603-22UF,6.3V,20%,X6S,A
P1V0_AUX                 C123             1        Q_CAP_C0603-22UF,6.3V,20%,X6S,A
P1V0_AUX                 L6               1        Q_INDUCTOR_SMLF-BLM18PG121SN1DA
P1V0_AUX                 L8               1        Q_INDUCTOR_SMLF-BLM18PG121SN1DA
P1V0_AUX                 L13              1        Q_INDUCTOR_SMLF-BLM18PG121SN1DA
P1V0_AUX                 L15              1        Q_INDUCTOR_SMLF-BLM18PG121SN1DA
P1V0_AUX                 PC266            1        Q_CAP_0402-0.1UF,25V,10%,X7R,CA
P1V0_AUX                 PC267            1        Q_CAP_0805-22UF,4V,20%,X6S,TMPA
P1V0_AUX                 PC268            1        Q_CAP_0805-22UF,4V,20%,X6S,TMPA
P1V0_AUX                 PC269            1        Q_CAP_0805-22UF,4V,20%,X6S,TMPA
P1V0_AUX                 PC270            1        Q_CAP_0805-22UF,4V,20%,X6S,TMPA
P1V0_AUX                 PL33             2        Q_INDUCTOR_SMLF-1UH,IND,CV-10BA
P1V0_AUX                 PU42             12       NB695GDZ-NB695GD-Z,SMLF,IC,AL0A
P1V0_AUX                 R279             1        Q_RES_0402LF-0,5%,1/16W,CHIP,CA
P1V0_AUX                 R281             1        Q_RES_0402LF-0,5%,1/16W,CHIP,CA
P1V0_AUX                 R796             1        Q_RES_0402LF-1K,1%,1/16W,CHIP,A
P1V0_AUX                 U5               L9       AST2600A1GP-AST2600A1-GP,SMLF,A
P1V0_AUX                 U5               L10      AST2600A1GP-AST2600A1-GP,SMLF,A
P1V0_AUX                 U5               M8       AST2600A1GP-AST2600A1-GP,SMLF,A
P1V0_AUX                 U5               M11      AST2600A1GP-AST2600A1-GP,SMLF,A
P1V0_AUX                 U5               N8       AST2600A1GP-AST2600A1-GP,SMLF,A
P1V0_AUX                 U5               N11      AST2600A1GP-AST2600A1-GP,SMLF,A
P1V0_AUX                 U5               P8       AST2600A1GP-AST2600A1-GP,SMLF,A
P1V0_AUX                 U5               P11      AST2600A1GP-AST2600A1-GP,SMLF,A
P1V0_AUX                 U5               R9       AST2600A1GP-AST2600A1-GP,SMLF,A
P1V0_AUX                 U5               R10      AST2600A1GP-AST2600A1-GP,SMLF,A
P1V0_AUX                 U43              5        TPS3808G33DBVR-TPS3808G33DBVR,A
P1V0_AUX_MODE            PR543            1        Q_RES_0402LF-100K,0.1%,1/16W,CA
P1V0_AUX_MODE            PU42             7        NB695GDZ-NB695GD-Z,SMLF,IC,AL0A
P1V0_AUX_VCC             PC260            1        Q_CAP_C0402-1UF,25V,10%,X6S,CHA
P1V0_AUX_VCC             PR541            2        Q_RES_0402LF-5.1,5%,1/16W,CHIPA
P1V0_AUX_VCC             PU42             3        NB695GDZ-NB695GD-Z,SMLF,IC,AL0A
P1V0_AUX_VCC             PU42             6        NB695GDZ-NB695GD-Z,SMLF,IC,AL0A
P1V0_AUX_VCC             PU42             10       NB695GDZ-NB695GD-Z,SMLF,IC,AL0A
P1V0_SENSOR              C311             1        Q_CAP_0402-0.1UF,25V,10%,X7R,CA
P1V0_SENSOR              R796             2        Q_RES_0402LF-1K,1%,1/16W,CHIP,A
P1V0_SENSOR              U5               AB17     AST2600A1GP-AST2600A1-GP,SMLF,A
P1V0_STBY_DP_VCC10A      C90              1        Q_CAP_C0402-1UF,25V,10%,X6S,CHA
P1V0_STBY_DP_VCC10A      C97              1        Q_CAP_0402-0.1UF,25V,10%,X7R,CA
P1V0_STBY_DP_VCC10A      L15              2        Q_INDUCTOR_SMLF-BLM18PG121SN1DA
P1V0_STBY_DP_VCC10A      U5               T8       AST2600A1GP-AST2600A1-GP,SMLF,A
P1V0_STBY_PE_VCC10A      C78              1        Q_CAP_C0402-1UF,25V,10%,X6S,CHA
P1V0_STBY_PE_VCC10A      C79              1        Q_CAP_0402-0.1UF,25V,10%,X7R,CA
P1V0_STBY_PE_VCC10A      L13              2        Q_INDUCTOR_SMLF-BLM18PG121SN1DA
P1V0_STBY_PE_VCC10A      U5               T9       AST2600A1GP-AST2600A1-GP,SMLF,A
P1V0_STBY_PLAVDD         C52              1        Q_CAP_C0402-1UF,25V,10%,X6S,CHA
P1V0_STBY_PLAVDD         C54              1        Q_CAP_0402-0.1UF,25V,10%,X7R,CA
P1V0_STBY_PLAVDD         C56              1        Q_CAP_C0402-1UF,25V,10%,X6S,CHA
P1V0_STBY_PLAVDD         C59              1        Q_CAP_0402-0.1UF,25V,10%,X7R,CA
P1V0_STBY_PLAVDD         C64              1        Q_CAP_C0402-1UF,25V,10%,X6S,CHA
P1V0_STBY_PLAVDD         C68              1        Q_CAP_0402-0.1UF,25V,10%,X7R,CA
P1V0_STBY_PLAVDD         L8               2        Q_INDUCTOR_SMLF-BLM18PG121SN1DA
P1V0_STBY_PLAVDD         U5               E7       AST2600A1GP-AST2600A1-GP,SMLF,A
P1V0_STBY_PLAVDD         U5               E9       AST2600A1GP-AST2600A1-GP,SMLF,A
P1V0_STBY_PLAVDD         U5               F7       AST2600A1GP-AST2600A1-GP,SMLF,A
P1V0_STBY_PLAVDD         U5               F9       AST2600A1GP-AST2600A1-GP,SMLF,A
P1V0_STBY_PLAVDD         U5               J9       AST2600A1GP-AST2600A1-GP,SMLF,A
P1V0_STBY_RC_VCC10A      C47              1        Q_CAP_C0402-1UF,25V,10%,X6S,CHA
P1V0_STBY_RC_VCC10A      C50              1        Q_CAP_0402-0.1UF,25V,10%,X7R,CA
P1V0_STBY_RC_VCC10A      L6               2        Q_INDUCTOR_SMLF-BLM18PG121SN1DA
P1V0_STBY_RC_VCC10A      U5               T10      AST2600A1GP-AST2600A1-GP,SMLF,A
P1V2_AUX                 C1               1        Q_CAP_C0603-4.7UF,25V,10%,X6S,A
P1V2_AUX                 C2               1        Q_CAP_C0402-1UF,25V,10%,X6S,CHA
P1V2_AUX                 C3               1        Q_CAP_C0402-1UF,25V,10%,X6S,CHA
P1V2_AUX                 C4               1        Q_CAP_C0402-1UF,25V,10%,X6S,CHA
P1V2_AUX                 C5               1        Q_CAP_C0402-1UF,25V,10%,X6S,CHA
P1V2_AUX                 C7               1        Q_CAP_0402-0.1UF,25V,10%,X7R,CA
P1V2_AUX                 C9               1        Q_CAP_0402-100PF,50V,5%,NPO,CHA
P1V2_AUX                 C13              1        Q_CAP_0402-0.1UF,25V,10%,X7R,CA
P1V2_AUX                 C14              1        Q_CAP_0402-0.1UF,25V,10%,X7R,CA
P1V2_AUX                 C15              1        Q_CAP_C0402-10UF,6.3V,20%,X6S,A
P1V2_AUX                 C16              1        Q_CAP_C0402-10UF,6.3V,20%,X6S,A
P1V2_AUX                 C17              1        Q_CAP_0402-0.1UF,25V,10%,X7R,CA
P1V2_AUX                 C18              1        Q_CAP_0402-0.1UF,25V,10%,X7R,CA
P1V2_AUX                 C55              1        Q_CAP_C0603-22UF,6.3V,20%,X6S,A
P1V2_AUX                 C58              1        Q_CAP_C0402-1UF,25V,10%,X6S,CHA
P1V2_AUX                 C62              1        Q_CAP_C0402-1UF,25V,10%,X6S,CHA
P1V2_AUX                 C66              1        Q_CAP_0402-0.1UF,25V,10%,X7R,CA
P1V2_AUX                 C70              1        Q_CAP_0402-0.1UF,25V,10%,X7R,CA
P1V2_AUX                 C72              1        Q_CAP_0402-0.1UF,25V,10%,X7R,CA
P1V2_AUX                 C74              1        Q_CAP_0402-0.1UF,25V,10%,X7R,CA
P1V2_AUX                 C76              1        Q_CAP_0402-0.1UF,25V,10%,X7R,CA
P1V2_AUX                 C82              1        Q_CAP_0402-0.1UF,25V,10%,X7R,CA
P1V2_AUX                 C84              1        Q_CAP_0402-0.1UF,25V,10%,X7R,CA
P1V2_AUX                 C91              1        Q_CAP_0402-0.1UF,25V,10%,X7R,CA
P1V2_AUX                 C98              1        Q_CAP_0402-0.1UF,25V,10%,X7R,CA
P1V2_AUX                 C103             1        Q_CAP_0402-0.1UF,25V,10%,X7R,CA
P1V2_AUX                 C107             1        Q_CAP_0402-0.1UF,25V,10%,X7R,CA
P1V2_AUX                 C112             1        Q_CAP_0402-0.1UF,25V,10%,X7R,CA
P1V2_AUX                 C117             1        Q_CAP_C0402-1UF,25V,10%,X6S,CHA
P1V2_AUX                 C122             1        Q_CAP_C0402-1UF,25V,10%,X6S,CHA
P1V2_AUX                 C127             1        Q_CAP_C0402-1UF,25V,10%,X6S,CHA
P1V2_AUX                 C129             1        Q_CAP_C0402-1UF,25V,10%,X6S,CHA
P1V2_AUX                 C131             1        Q_CAP_C0603-22UF,10V,20%,X5R,CA
P1V2_AUX                 C132             1        Q_CAP_C0603-22UF,10V,20%,X5R,CA
P1V2_AUX                 C169             1        Q_CAP_C0402-0.01UF,50V,10%,EMPA
P1V2_AUX                 C221             1        Q_CAP_0402-0.1UF,25V,10%,X7R,CA
P1V2_AUX                 C222             1        Q_CAP_0402-0.1UF,25V,10%,X7R,CA
P1V2_AUX                 C225             1        Q_CAP_0402-0.1UF,25V,10%,X7R,CA
P1V2_AUX                 C229             2        Q_CAP_0402-0.22UF,16V,10%,EMPTA
P1V2_AUX                 L2               1        Q_INDUCTOR_SMLF-BLM18PG121SN1DB
P1V2_AUX                 L11              1        Q_INDUCTOR_SMLF-BLM18PG121SN1DA
P1V2_AUX                 PC255            1        Q_CAP_0402-0.1UF,25V,10%,X7R,CA
P1V2_AUX                 PC256            1        Q_CAP_0805-22UF,4V,20%,X6S,TMPA
P1V2_AUX                 PC257            1        Q_CAP_0805-22UF,4V,20%,X6S,TMPA
P1V2_AUX                 PC258            1        Q_CAP_0805-22UF,4V,20%,X6S,TMPA
P1V2_AUX                 PC259            1        Q_CAP_0805-22UF,4V,20%,X6S,TMPA
P1V2_AUX                 PL31             2        Q_INDUCTOR_SMLF-1UH,IND,CV-10BA
P1V2_AUX                 PU41             12       NB695GDZ-NB695GD-Z,SMLF,IC,AL0A
P1V2_AUX                 R9               2        Q_RES_0402LF-4.7K,5%,1/16W,CHIA
P1V2_AUX                 R278             1        Q_RES_0402LF-0,5%,1/16W,EMPTY,A
P1V2_AUX                 R280             1        Q_RES_0402LF-0,5%,1/16W,EMPTY,A
P1V2_AUX                 R324             1        Q_RES_0402LF-1K,1%,1/16W,CHIP,A
P1V2_AUX                 R351             2        Q_RES_0402LF-120,1%,1/16W,CHIPA
P1V2_AUX                 R352             2        Q_RES_0402LF-120,1%,1/16W,CHIPA
P1V2_AUX                 R353             2        Q_RES_0402LF-120,1%,1/16W,CHIPA
P1V2_AUX                 R354             2        Q_RES_0402LF-120,1%,1/16W,CHIPA
P1V2_AUX                 R355             2        Q_RES_0402LF-120,1%,1/16W,CHIPA
P1V2_AUX                 R356             2        Q_RES_0402LF-120,1%,1/16W,CHIPA
P1V2_AUX                 R357             2        Q_RES_0402LF-120,1%,1/16W,CHIPA
P1V2_AUX                 R358             2        Q_RES_0402LF-120,1%,1/16W,CHIPA
P1V2_AUX                 R359             2        Q_RES_0402LF-120,1%,1/16W,CHIPA
P1V2_AUX                 R360             2        Q_RES_0402LF-120,1%,1/16W,CHIPA
P1V2_AUX                 R361             2        Q_RES_0402LF-120,1%,1/16W,CHIPA
P1V2_AUX                 R362             2        Q_RES_0402LF-120,1%,1/16W,CHIPA
P1V2_AUX                 R363             2        Q_RES_0402LF-120,1%,1/16W,CHIPA
P1V2_AUX                 R364             2        Q_RES_0402LF-120,1%,1/16W,CHIPA
P1V2_AUX                 R365             2        Q_RES_0402LF-120,1%,1/16W,CHIPA
P1V2_AUX                 R366             2        Q_RES_0402LF-120,1%,1/16W,CHIPA
P1V2_AUX                 R367             2        Q_RES_0402LF-120,1%,1/16W,CHIPA
P1V2_AUX                 R368             2        Q_RES_0402LF-120,1%,1/16W,CHIPA
P1V2_AUX                 R369             2        Q_RES_0402LF-120,1%,1/16W,CHIPA
P1V2_AUX                 R370             2        Q_RES_0402LF-120,1%,1/16W,CHIPA
P1V2_AUX                 R371             2        Q_RES_0402LF-120,1%,1/16W,CHIPA
P1V2_AUX                 R372             2        Q_RES_0402LF-120,1%,1/16W,CHIPA
P1V2_AUX                 R373             2        Q_RES_0402LF-120,1%,1/16W,CHIPA
P1V2_AUX                 R374             2        Q_RES_0402LF-120,1%,1/16W,CHIPA
P1V2_AUX                 R375             2        Q_RES_0402LF-120,1%,1/16W,EMPTA
P1V2_AUX                 R782             1        Q_RES_0402LF-0,5%,1/16W,EMPTY,A
P1V2_AUX                 R784             1        Q_RES_0402LF-0,5%,1/16W,EMPTY,A
P1V2_AUX                 R795             1        Q_RES_0402LF-1K,1%,1/16W,CHIP,A
P1V2_AUX                 U1               A1       K4A8G165WCBCTD-K4A8G165WC-BCTDA
P1V2_AUX                 U1               A9       K4A8G165WCBCTD-K4A8G165WC-BCTDA
P1V2_AUX                 U1               B3       K4A8G165WCBCTD-K4A8G165WC-BCTDA
P1V2_AUX                 U1               B9       K4A8G165WCBCTD-K4A8G165WC-BCTDA
P1V2_AUX                 U1               C1       K4A8G165WCBCTD-K4A8G165WC-BCTDA
P1V2_AUX                 U1               D1       K4A8G165WCBCTD-K4A8G165WC-BCTDA
P1V2_AUX                 U1               D9       K4A8G165WCBCTD-K4A8G165WC-BCTDA
P1V2_AUX                 U1               F2       K4A8G165WCBCTD-K4A8G165WC-BCTDA
P1V2_AUX                 U1               F8       K4A8G165WCBCTD-K4A8G165WC-BCTDA
P1V2_AUX                 U1               G1       K4A8G165WCBCTD-K4A8G165WC-BCTDA
P1V2_AUX                 U1               G7       K4A8G165WCBCTD-K4A8G165WC-BCTDA
P1V2_AUX                 U1               G9       K4A8G165WCBCTD-K4A8G165WC-BCTDA
P1V2_AUX                 U1               J1       K4A8G165WCBCTD-K4A8G165WC-BCTDA
P1V2_AUX                 U1               J2       K4A8G165WCBCTD-K4A8G165WC-BCTDA
P1V2_AUX                 U1               J8       K4A8G165WCBCTD-K4A8G165WC-BCTDA
P1V2_AUX                 U1               J9       K4A8G165WCBCTD-K4A8G165WC-BCTDA
P1V2_AUX                 U1               L1       K4A8G165WCBCTD-K4A8G165WC-BCTDA
P1V2_AUX                 U1               L9       K4A8G165WCBCTD-K4A8G165WC-BCTDA
P1V2_AUX                 U1               R1       K4A8G165WCBCTD-K4A8G165WC-BCTDA
P1V2_AUX                 U1               T9       K4A8G165WCBCTD-K4A8G165WC-BCTDA
P1V2_AUX                 U5               G6       AST2600A1GP-AST2600A1-GP,SMLF,A
P1V2_AUX                 U5               H6       AST2600A1GP-AST2600A1-GP,SMLF,A
P1V2_AUX                 U5               J6       AST2600A1GP-AST2600A1-GP,SMLF,A
P1V2_AUX                 U5               K6       AST2600A1GP-AST2600A1-GP,SMLF,A
P1V2_AUX                 U5               K16      AST2600A1GP-AST2600A1-GP,SMLF,A
P1V2_AUX                 U5               K17      AST2600A1GP-AST2600A1-GP,SMLF,A
P1V2_AUX                 U5               K18      AST2600A1GP-AST2600A1-GP,SMLF,A
P1V2_AUX                 U5               K19      AST2600A1GP-AST2600A1-GP,SMLF,A
P1V2_AUX                 U5               L6       AST2600A1GP-AST2600A1-GP,SMLF,A
P1V2_AUX                 U5               L14      AST2600A1GP-AST2600A1-GP,SMLF,A
P1V2_AUX                 U5               L21      AST2600A1GP-AST2600A1-GP,SMLF,A
P1V2_AUX                 U5               M14      AST2600A1GP-AST2600A1-GP,SMLF,A
P1V2_AUX                 U5               M21      AST2600A1GP-AST2600A1-GP,SMLF,A
P1V2_AUX                 U5               N14      AST2600A1GP-AST2600A1-GP,SMLF,A
P1V2_AUX                 U5               N21      AST2600A1GP-AST2600A1-GP,SMLF,A
P1V2_AUX                 U5               P6       AST2600A1GP-AST2600A1-GP,SMLF,A
P1V2_AUX                 U5               P14      AST2600A1GP-AST2600A1-GP,SMLF,A
P1V2_AUX                 U5               P21      AST2600A1GP-AST2600A1-GP,SMLF,A
P1V2_AUX                 U5               R6       AST2600A1GP-AST2600A1-GP,SMLF,A
P1V2_AUX                 U5               R14      AST2600A1GP-AST2600A1-GP,SMLF,A
P1V2_AUX                 U5               R21      AST2600A1GP-AST2600A1-GP,SMLF,A
P1V2_AUX                 U5               T6       AST2600A1GP-AST2600A1-GP,SMLF,A
P1V2_AUX                 U5               T14      AST2600A1GP-AST2600A1-GP,SMLF,A
P1V2_AUX                 U5               T21      AST2600A1GP-AST2600A1-GP,SMLF,A
P1V2_AUX                 U5               U15      AST2600A1GP-AST2600A1-GP,SMLF,A
P1V2_AUX                 U5               U16      AST2600A1GP-AST2600A1-GP,SMLF,A
P1V2_AUX                 U5               U17      AST2600A1GP-AST2600A1-GP,SMLF,A
P1V2_AUX                 U5               U18      AST2600A1GP-AST2600A1-GP,SMLF,A
P1V2_AUX_MODE            PR496            1        Q_RES_0402LF-150K,1%,1/16W,CHIA
P1V2_AUX_MODE            PU41             7        NB695GDZ-NB695GD-Z,SMLF,IC,AL0A
P1V2_AUX_VCC             PC250            1        Q_CAP_C0402-1UF,25V,10%,X6S,CHA
P1V2_AUX_VCC             PR539            2        Q_RES_0402LF-5.1,5%,1/16W,CHIPA
P1V2_AUX_VCC             PU41             6        NB695GDZ-NB695GD-Z,SMLF,IC,AL0A
P1V2_AUX_VCC             PU41             10       NB695GDZ-NB695GD-Z,SMLF,IC,AL0A
P1V2_P1V0_I3C_VDDL1      C139             1        Q_CAP_0402-0.1UF,25V,10%,X7R,CA
P1V2_P1V0_I3C_VDDL1      R188             1        Q_RES_0402LF-4.7K,5%,1/16W,CHIA
P1V2_P1V0_I3C_VDDL1      R189             1        Q_RES_0402LF-4.7K,5%,1/16W,CHIA
P1V2_P1V0_I3C_VDDL1      R190             1        Q_RES_0402LF-4.7K,5%,1/16W,CHIA
P1V2_P1V0_I3C_VDDL1      R191             1        Q_RES_0402LF-4.7K,5%,1/16W,CHIA
P1V2_P1V0_I3C_VDDL1      R194             1        Q_RES_0402LF-4.7K,5%,1/16W,CHIA
P1V2_P1V0_I3C_VDDL1      R195             1        Q_RES_0402LF-4.7K,5%,1/16W,CHIA
P1V2_P1V0_I3C_VDDL1      R196             1        Q_RES_0402LF-4.7K,5%,1/16W,CHIA
P1V2_P1V0_I3C_VDDL1      R197             1        Q_RES_0402LF-4.7K,5%,1/16W,CHIA
P1V2_P1V0_I3C_VDDL1      R278             2        Q_RES_0402LF-0,5%,1/16W,EMPTY,A
P1V2_P1V0_I3C_VDDL1      R279             2        Q_RES_0402LF-0,5%,1/16W,CHIP,CA
P1V2_P1V0_I3C_VDDL1      U5               V22      AST2600A1GP-AST2600A1-GP,SMLF,A
P1V2_P1V0_I3C_VDDL2      C140             1        Q_CAP_0402-0.1UF,25V,10%,X7R,CA
P1V2_P1V0_I3C_VDDL2      R280             2        Q_RES_0402LF-0,5%,1/16W,EMPTY,A
P1V2_P1V0_I3C_VDDL2      R281             2        Q_RES_0402LF-0,5%,1/16W,CHIP,CA
P1V2_P1V0_I3C_VDDL2      U5               U21      AST2600A1GP-AST2600A1-GP,SMLF,A
P1V2_PHY0                C305             1        Q_CAP_0402-0.1UF,10V,10%,X7R,TA
P1V2_PHY0                C332             1        Q_CAP_0402-0.1UF,10V,10%,X7R,TA
P1V2_PHY0                C349             1        Q_CAP_C0402-22UF,6.3V,20%,X5R,A
P1V2_PHY0                L32              2        Q_INDUCTOR_SMLF-BLM15PX121SN1DA
P1V2_PHY0                L33              2        Q_INDUCTOR_SMLF-BLM15PX121SN1DA
P1V2_PHY0                U7               2        BCM54612EB1KMLG-BCM54612EB1KMLA
P1V2_PHY0                U7               3        BCM54612EB1KMLG-BCM54612EB1KMLA
P1V2_PHY0                U7               30       BCM54612EB1KMLG-BCM54612EB1KMLA
P1V2_PHY0_AVDDL          C297             1        Q_CAP_0402-0.1UF,10V,10%,X7R,TA
P1V2_PHY0_AVDDL          C328             1        Q_CAP_0402-0.1UF,10V,10%,X7R,TA
P1V2_PHY0_AVDDL          C347             1        Q_CAP_0402-4.7UF,10V,10%,X5R,CA
P1V2_PHY0_AVDDL          L32              1        Q_INDUCTOR_SMLF-BLM15PX121SN1DA
P1V2_PHY0_AVDDL          U7               13       BCM54612EB1KMLG-BCM54612EB1KMLA
P1V2_PHY0_AVDDL          U7               19       BCM54612EB1KMLG-BCM54612EB1KMLA
P1V2_PHY0_AVDDL          U7               25       BCM54612EB1KMLG-BCM54612EB1KMLA
P1V2_PHY0_PLLVDD         C265             1        Q_CAP_0402-0.1UF,10V,10%,X7R,TA
P1V2_PHY0_PLLVDD         C346             1        Q_CAP_C0402-22UF,6.3V,20%,X5R,A
P1V2_PHY0_PLLVDD         L33              1        Q_INDUCTOR_SMLF-BLM15PX121SN1DA
P1V2_PHY0_PLLVDD         U7               11       BCM54612EB1KMLG-BCM54612EB1KMLA
P1V2_SENSOR              C309             1        Q_CAP_0402-0.1UF,25V,10%,X7R,CA
P1V2_SENSOR              R795             2        Q_RES_0402LF-1K,1%,1/16W,CHIP,A
P1V2_SENSOR              U5               AB18     AST2600A1GP-AST2600A1-GP,SMLF,A
P1V2_STBY_MVDD_CK        C63              1        Q_CAP_0402-2200PF,50V,10%,X7R,A
P1V2_STBY_MVDD_CK        C67              1        Q_CAP_C0402-1UF,25V,10%,X6S,CHA
P1V2_STBY_MVDD_CK        C71              1        Q_CAP_0402-0.1UF,25V,10%,X7R,CA
P1V2_STBY_MVDD_CK        C73              1        Q_CAP_0402-0.1UF,25V,10%,X7R,CA
P1V2_STBY_MVDD_CK        L11              2        Q_INDUCTOR_SMLF-BLM18PG121SN1DA
P1V2_STBY_MVDD_CK        U5               M6       AST2600A1GP-AST2600A1-GP,SMLF,A
P1V8_AUX                 C87              1        Q_CAP_0402-0.1UF,25V,10%,X7R,CA
P1V8_AUX                 C89              1        Q_CAP_0402-0.1UF,25V,10%,X7R,CA
P1V8_AUX                 C93              1        Q_CAP_0402-0.1UF,25V,10%,X7R,CA
P1V8_AUX                 C95              1        Q_CAP_0402-0.1UF,25V,10%,X7R,CA
P1V8_AUX                 C100             1        Q_CAP_0402-0.1UF,25V,10%,X7R,CA
P1V8_AUX                 C102             1        Q_CAP_0402-0.1UF,25V,10%,X7R,CA
P1V8_AUX                 C105             1        Q_CAP_0402-0.1UF,25V,10%,X7R,CA
P1V8_AUX                 C106             1        Q_CAP_C0402-1UF,25V,10%,X6S,CHA
P1V8_AUX                 C109             1        Q_CAP_0402-0.1UF,25V,10%,X7R,CA
P1V8_AUX                 C111             1        Q_CAP_C0402-1UF,25V,10%,X6S,CHA
P1V8_AUX                 C114             1        Q_CAP_C0402-1UF,25V,10%,X6S,CHA
P1V8_AUX                 C116             1        Q_CAP_C0402-1UF,25V,10%,X6S,CHA
P1V8_AUX                 C119             1        Q_CAP_C0402-1UF,25V,10%,X6S,CHA
P1V8_AUX                 C121             1        Q_CAP_C0603-22UF,6.3V,20%,X6S,A
P1V8_AUX                 C124             1        Q_CAP_C0603-22UF,6.3V,20%,X6S,A
P1V8_AUX                 C126             1        Q_CAP_C0603-22UF,6.3V,20%,X6S,A
P1V8_AUX                 C226             1        Q_CAP_0402-0.1UF,10V,10%,EMPTYA
P1V8_AUX                 C227             1        Q_CAP_0402-0.1UF,10V,10%,EMPTYA
P1V8_AUX                 C232             1        Q_CAP_C0603-22UF,6.3V,20%,EMPTA
P1V8_AUX                 C233             1        Q_CAP_0402-0.1UF,10V,10%,EMPTYA
P1V8_AUX                 L3               1        Q_INDUCTOR_SMLF-BLM18PG121SN1DA
P1V8_AUX                 L5               1        Q_INDUCTOR_SMLF-BLM18PG121SN1DA
P1V8_AUX                 L10              1        Q_INDUCTOR_SMLF-BLM18PG121SN1DA
P1V8_AUX                 L14              1        Q_INDUCTOR_SMLF-BLM18PG121SN1DA
P1V8_AUX                 L16              1        Q_INDUCTOR_SMLF-BLM18PG121SN1DA
P1V8_AUX                 PC248            1        Q_CAP_C0805-10UF,25V,10%,X6S,CA
P1V8_AUX                 PC249            1        Q_CAP_0402-0.1UF,25V,10%,X7R,CA
P1V8_AUX                 PU40             1        RT9059GQW-RT9059GQW,SMLF,IC,ALA
P1V8_AUX                 PU40             2        RT9059GQW-RT9059GQW,SMLF,IC,ALA
P1V8_AUX                 PU40             3        RT9059GQW-RT9059GQW,SMLF,IC,ALA
P1V8_AUX                 Q8               3        MOSFET_DUAL_6P-DMN2400UV-7,SMLA
P1V8_AUX                 R154             1        Q_RES_0402LF-0,5%,1/16W,EMPTY,A
P1V8_AUX                 R164             1        Q_RES_0402LF-10K,1%,1/16W,EMPTA
P1V8_AUX                 R208             1        Q_RES_0402LF-0,5%,1/16W,EMPTY,A
P1V8_AUX                 R214             1        Q_RES_0402LF-0,5%,1/16W,EMPTY,A
P1V8_AUX                 R232             1        Q_RES_0402LF-0,5%,1/16W,EMPTY,A
P1V8_AUX                 R655             1        Q_RES_0402LF-10K,1%,1/16W,EMPTA
P1V8_AUX                 R656             1        Q_RES_0402LF-10K,1%,1/16W,EMPTA
P1V8_AUX                 R657             1        Q_RES_0402LF-10K,1%,1/16W,EMPTA
P1V8_AUX                 R658             1        Q_RES_0402LF-10K,1%,1/16W,EMPTA
P1V8_AUX                 R659             1        Q_RES_0402LF-10K,1%,1/16W,EMPTA
P1V8_AUX                 R660             1        Q_RES_0402LF-10K,1%,1/16W,EMPTA
P1V8_AUX                 R661             1        Q_RES_0402LF-10K,1%,1/16W,EMPTA
P1V8_AUX                 R662             1        Q_RES_0402LF-10K,1%,1/16W,EMPTA
P1V8_AUX                 R663             1        Q_RES_0402LF-10K,1%,1/16W,EMPTA
P1V8_AUX                 R686             1        Q_RES_0402LF-4.7K,5%,1/16W,EMPA
P1V8_AUX                 R687             1        Q_RES_0402LF-4.7K,5%,1/16W,EMPA
P1V8_AUX                 R781             1        Q_RES_0402LF-0,5%,1/16W,EMPTY,A
P1V8_AUX                 R783             1        Q_RES_0402LF-0,5%,1/16W,CHIP,CA
P1V8_AUX                 R793             1        Q_RES_0402LF-665,1%,1/16W,CHIPA
P1V8_AUX                 R831             1        Q_RES_0402LF-15K,1%,1/16W,CHIPA
P1V8_AUX                 U5               H8       AST2600A1GP-AST2600A1-GP,SMLF,A
P1V8_AUX                 U5               H12      AST2600A1GP-AST2600A1-GP,SMLF,A
P1V8_AUX                 U5               J8       AST2600A1GP-AST2600A1-GP,SMLF,A
P1V8_AUX                 U5               J12      AST2600A1GP-AST2600A1-GP,SMLF,A
P1V8_AUX                 U5               L13      AST2600A1GP-AST2600A1-GP,SMLF,A
P1V8_AUX                 U5               M13      AST2600A1GP-AST2600A1-GP,SMLF,A
P1V8_AUX                 U5               N12      AST2600A1GP-AST2600A1-GP,SMLF,A
P1V8_AUX                 U5               N13      AST2600A1GP-AST2600A1-GP,SMLF,A
P1V8_AUX                 U5               P12      AST2600A1GP-AST2600A1-GP,SMLF,A
P1V8_AUX                 U5               P13      AST2600A1GP-AST2600A1-GP,SMLF,A
P1V8_AUX                 U5               R12      AST2600A1GP-AST2600A1-GP,SMLF,A
P1V8_AUX                 U5               R13      AST2600A1GP-AST2600A1-GP,SMLF,A
P1V8_AUX                 U5               T13      AST2600A1GP-AST2600A1-GP,SMLF,A
P1V8_AUX                 U5               U6       AST2600A1GP-AST2600A1-GP,SMLF,A
P1V8_AUX                 U5               U13      AST2600A1GP-AST2600A1-GP,SMLF,A
P1V8_AUX                 U5               V6       AST2600A1GP-AST2600A1-GP,SMLF,A
P1V8_AUX                 U5               V13      AST2600A1GP-AST2600A1-GP,SMLF,A
P1V8_AUX                 U5               W13      AST2600A1GP-AST2600A1-GP,SMLF,A
P1V8_AUX                 U5               W14      AST2600A1GP-AST2600A1-GP,SMLF,A
P1V8_AUX                 U20              C6       MTFC8GAKAJCN1MWT-MTFC8GAKAJCN-A
P1V8_AUX                 U20              M4       MTFC8GAKAJCN1MWT-MTFC8GAKAJCN-A
P1V8_AUX                 U20              N4       MTFC8GAKAJCN1MWT-MTFC8GAKAJCN-A
P1V8_AUX                 U20              P3       MTFC8GAKAJCN1MWT-MTFC8GAKAJCN-A
P1V8_AUX                 U20              P5       MTFC8GAKAJCN1MWT-MTFC8GAKAJCN-A
P1V8_BMC_USB2AV18        C40              1        Q_CAP_C0402-4.7UF,10V,10%,X5R,A
P1V8_BMC_USB2AV18        C41              1        Q_CAP_0402-0.1UF,25V,10%,X7R,CA
P1V8_BMC_USB2AV18        L3               2        Q_INDUCTOR_SMLF-BLM18PG121SN1DA
P1V8_BMC_USB2AV18        U5               K10      AST2600A1GP-AST2600A1-GP,SMLF,A
P1V8_SENSOR              C307             1        Q_CAP_0402-0.1UF,25V,10%,X7R,CA
P1V8_SENSOR              R793             2        Q_RES_0402LF-665,1%,1/16W,CHIPA
P1V8_SENSOR              R794             1        Q_RES_0402LF-2K,1%,1/16W,CHIP,A
P1V8_SENSOR              U5               AC19     AST2600A1GP-AST2600A1-GP,SMLF,A
P1V8_STBY_AVDDPLL        C46              1        Q_CAP_C0402-1UF,25V,10%,X6S,CHA
P1V8_STBY_AVDDPLL        C49              1        Q_CAP_0402-0.1UF,25V,10%,X7R,CA
P1V8_STBY_AVDDPLL        L5               2        Q_INDUCTOR_SMLF-BLM18PG121SN1DA
P1V8_STBY_AVDDPLL        U5               N5       AST2600A1GP-AST2600A1-GP,SMLF,A
P1V8_STBY_DP_VCC18A      C128             1        Q_CAP_C0402-1UF,25V,10%,X6S,CHA
P1V8_STBY_DP_VCC18A      C130             1        Q_CAP_0402-0.1UF,25V,10%,X7R,CA
P1V8_STBY_DP_VCC18A      L16              2        Q_INDUCTOR_SMLF-BLM18PG121SN1DA
P1V8_STBY_DP_VCC18A      U5               V8       AST2600A1GP-AST2600A1-GP,SMLF,A
P1V8_STBY_PE_VCC18A      C61              1        Q_CAP_C0402-1UF,25V,10%,X6S,CHA
P1V8_STBY_PE_VCC18A      C69              1        Q_CAP_0402-0.1UF,25V,10%,X7R,CA
P1V8_STBY_PE_VCC18A      L10              2        Q_INDUCTOR_SMLF-BLM18PG121SN1DA
P1V8_STBY_PE_VCC18A      U5               V9       AST2600A1GP-AST2600A1-GP,SMLF,A
P1V8_STBY_RC_VCC18A      C80              1        Q_CAP_C0402-1UF,25V,10%,X6S,CHA
P1V8_STBY_RC_VCC18A      C81              1        Q_CAP_0402-0.1UF,25V,10%,X7R,CA
P1V8_STBY_RC_VCC18A      L14              2        Q_INDUCTOR_SMLF-BLM18PG121SN1DA
P1V8_STBY_RC_VCC18A      U5               V10      AST2600A1GP-AST2600A1-GP,SMLF,A
P2E_BMC_RX_DN            C25              1        Q_CAP_0402-0.1UF,25V,10%,X7R,CA
P2E_BMC_RX_DN            U5               AE5      AST2600A1GP-AST2600A1-GP,SMLF,A
P2E_BMC_RX_DP            C24              1        Q_CAP_0402-0.1UF,25V,10%,X7R,CA
P2E_BMC_RX_DP            U5               AE4      AST2600A1GP-AST2600A1-GP,SMLF,A
P2V5_AUX                 C6               1        Q_CAP_0402-0.1UF,25V,10%,X7R,CA
P2V5_AUX                 C8               1        Q_CAP_0402-0.1UF,25V,10%,X7R,CA
P2V5_AUX                 PC235            1        Q_CAP_0402-0.1UF,25V,10%,X7R,CA
P2V5_AUX                 PC237            1        Q_CAP_C0805-10UF,25V,10%,X6S,CA
P2V5_AUX                 PU39             1        RT9059GQW-RT9059GQW,SMLF,IC,ALA
P2V5_AUX                 PU39             2        RT9059GQW-RT9059GQW,SMLF,IC,ALA
P2V5_AUX                 PU39             3        RT9059GQW-RT9059GQW,SMLF,IC,ALA
P2V5_AUX                 R156             1        Q_RES_0402LF-0,5%,1/16W,EMPTY,A
P2V5_AUX                 R779             1        Q_RES_0402LF-0,5%,1/16W,CHIP,CA
P2V5_AUX                 R780             1        Q_RES_0402LF-0,5%,1/16W,EMPTY,A
P2V5_AUX                 R791             1        Q_RES_0402LF-1.69K,1%,1/16W,CHA
P2V5_AUX                 R829             1        Q_RES_0402LF-25.5K,1%,1/16W,CHA
P2V5_AUX                 U1               B1       K4A8G165WCBCTD-K4A8G165WC-BCTDA
P2V5_AUX                 U1               R9       K4A8G165WCBCTD-K4A8G165WC-BCTDA
P2V5_SENSOR              C303             1        Q_CAP_0402-0.1UF,25V,10%,X7R,CA
P2V5_SENSOR              R791             2        Q_RES_0402LF-1.69K,1%,1/16W,CHA
P2V5_SENSOR              R792             1        Q_RES_0402LF-2K,1%,1/16W,CHIP,A
P2V5_SENSOR              U5               AD19     AST2600A1GP-AST2600A1-GP,SMLF,A
P3V3_AUX                 C19              1        Q_CAP_0402-0.1UF,25V,10%,X7R,CA
P3V3_AUX                 C20              1        Q_CAP_0402-0.1UF,25V,10%,X7R,CA
P3V3_AUX                 C34              1        Q_CAP_0402-0.1UF,25V,10%,X7R,CA
P3V3_AUX                 C88              1        Q_CAP_0402-0.1UF,25V,10%,X7R,CA
P3V3_AUX                 C94              1        Q_CAP_0402-0.1UF,25V,10%,X7R,CA
P3V3_AUX                 C101             1        Q_CAP_0402-0.1UF,25V,10%,X7R,CA
P3V3_AUX                 C110             1        Q_CAP_C0402-1UF,25V,10%,X6S,CHA
P3V3_AUX                 C115             1        Q_CAP_C0402-1UF,25V,10%,X6S,CHA
P3V3_AUX                 C120             1        Q_CAP_C0603-22UF,10V,20%,X5R,CA
P3V3_AUX                 C125             1        Q_CAP_C0603-22UF,10V,20%,X5R,CA
P3V3_AUX                 C143             1        Q_CAP_C0402-10UF,10V,20%,X5R,CA
P3V3_AUX                 C144             1        Q_CAP_0402-0.1UF,25V,10%,X7R,CA
P3V3_AUX                 C146             1        Q_CAP_0402-0.1UF,25V,10%,X7R,CA
P3V3_AUX                 C147             1        Q_CAP_0402-0.1UF,25V,10%,X7R,CA
P3V3_AUX                 C148             1        Q_CAP_0402-0.1UF,25V,10%,X7R,CA
P3V3_AUX                 C149             1        Q_CAP_0402-0.1UF,25V,10%,X7R,CA
P3V3_AUX                 C157             1        Q_CAP_0402-0.1UF,25V,10%,X7R,CA
P3V3_AUX                 C158             1        Q_CAP_0402-0.1UF,25V,10%,X7R,CA
P3V3_AUX                 C159             1        Q_CAP_0402-0.1UF,25V,10%,X7R,CA
P3V3_AUX                 C175             1        Q_CAP_0402-0.1UF,25V,10%,X7R,CA
P3V3_AUX                 C180             1        Q_CAP_C0402-0.1UF,16V,10%,X7R,A
P3V3_AUX                 C191             1        Q_CAP_0402-0.1UF,25V,10%,X7R,CA
P3V3_AUX                 C192             1        Q_CAP_0402-0.1UF,25V,10%,X7R,CA
P3V3_AUX                 C200             1        Q_CAP_0402-0.1UF,25V,10%,X7R,CA
P3V3_AUX                 C201             1        Q_CAP_0402-0.1UF,25V,10%,X7R,CA
P3V3_AUX                 C215             1        Q_CAP_C0402-10UF,10V,20%,X5R,CA
P3V3_AUX                 C217             1        Q_CAP_0402-0.1UF,25V,10%,X7R,CA
P3V3_AUX                 C228             1        Q_CAP_0402-0.1UF,10V,10%,EMPTYA
P3V3_AUX                 C234             1        Q_CAP_C0603-22UF,10V,20%,EMPTYA
P3V3_AUX                 C235             1        Q_CAP_0402-0.1UF,10V,10%,EMPTYA
P3V3_AUX                 C240             1        Q_CAP_C0402-0.1UF,16V,10%,X7R,A
P3V3_AUX                 C241             1        Q_CAP_0402-0.1UF,10V,10%,X7R,TA
P3V3_AUX                 C244             1        Q_CAP_C0402-1UF,25V,10%,X6S,CHA
P3V3_AUX                 C246             1        Q_CAP_C0402-0.01UF,50V,10%,X7RA
P3V3_AUX                 C248             1        Q_CAP_C0402-10UF,10V,20%,X5R,CA
P3V3_AUX                 C249             1        Q_CAP_0402-0.1UF,25V,10%,X7R,CA
P3V3_AUX                 C253             1        Q_CAP_0402-0.1UF,25V,10%,X7R,CA
P3V3_AUX                 C255             1        Q_CAP_0402-0.1UF,25V,10%,X7R,CA
P3V3_AUX                 C256             1        Q_CAP_C0402-1UF,25V,10%,X6S,CHA
P3V3_AUX                 C257             1        Q_CAP_C0402-1UF,25V,10%,X6S,CHA
P3V3_AUX                 C258             1        Q_CAP_C0402-0.01UF,50V,10%,X7RA
P3V3_AUX                 C259             1        Q_CAP_C0402-0.01UF,50V,10%,X7RA
P3V3_AUX                 C262             1        Q_CAP_C0402-10UF,6.3V,20%,X6S,A
P3V3_AUX                 C263             1        Q_CAP_0402-0.1UF,25V,10%,X7R,CA
P3V3_AUX                 C266             1        Q_CAP_0402-0.1UF,25V,10%,X7R,CA
P3V3_AUX                 C269             1        Q_CAP_0402-0.1UF,25V,10%,X7R,CA
P3V3_AUX                 C274             1        Q_CAP_0402-0.1UF,25V,10%,X7R,CA
P3V3_AUX                 C278             1        Q_CAP_0402-0.1UF,25V,10%,X7R,CA
P3V3_AUX                 C289             1        Q_CAP_0402-0.1UF,25V,10%,X7R,CA
P3V3_AUX                 C298             1        Q_CAP_0402-0.1UF,25V,10%,X7R,CA
P3V3_AUX                 C302             1        Q_CAP_0402-0.1UF,25V,10%,X7R,CA
P3V3_AUX                 C306             1        Q_CAP_0402-0.1UF,25V,10%,X7R,CA
P3V3_AUX                 C308             1        Q_CAP_0402-0.1UF,25V,10%,X7R,CA
P3V3_AUX                 C310             1        Q_CAP_0402-0.1UF,25V,10%,X7R,CA
P3V3_AUX                 C312             1        Q_CAP_0402-0.1UF,25V,10%,X7R,CA
P3V3_AUX                 C313             1        Q_CAP_0402-0.1UF,25V,10%,X7R,CA
P3V3_AUX                 C315             1        Q_CAP_0402-0.1UF,25V,10%,X7R,CA
P3V3_AUX                 C317             1        Q_CAP_0402-0.1UF,25V,10%,X7R,CA
P3V3_AUX                 C318             1        Q_CAP_0402-0.1UF,25V,10%,X7R,CA
P3V3_AUX                 C319             1        Q_CAP_0402-0.1UF,25V,10%,X7R,CA
P3V3_AUX                 C320             1        Q_CAP_0402-0.1UF,25V,10%,X7R,CA
P3V3_AUX                 C323             1        Q_CAP_0402-0.1UF,25V,10%,X7R,CA
P3V3_AUX                 C333             1        Q_CAP_0402-0.1UF,10V,10%,X7R,TA
P3V3_AUX                 C350             1        Q_CAP_0402-4.7UF,10V,10%,X5R,CA
P3V3_AUX                 D13              1        PCA9517ADP_SMLF-PCA9517ADP,IC,A
P3V3_AUX                 D13              8        PCA9517ADP_SMLF-PCA9517ADP,IC,A
P3V3_AUX                 J5               7        SCONN11_9192031111LF-SCONN11_9A
P3V3_AUX                 J7               1        CONN7_4400547-CONN7_440054-7,TA
P3V3_AUX                 J10              7        SCONN11_9192031111LF-SCONN11_9A
P3V3_AUX                 J40              2        SCONN16_ACASPI006P06-SCONN16_AA
P3V3_AUX                 J121             2        SCONN16_ACASPI006P06-SCONN16_AA
P3V3_AUX                 L4               1        Q_INDUCTOR_SMLF-BLM18PG121SN1DA
P3V3_AUX                 L7               1        Q_INDUCTOR_SMLF-BLM18PG121SN1DA
P3V3_AUX                 L9               1        Q_INDUCTOR_SMLF-BLM18PG121SN1DA
P3V3_AUX                 L12              1        Q_INDUCTOR_SMLF-BLM18PG121SN1DA
P3V3_AUX                 L18              2        Q_INDUCTOR_SMLF-BLM15PX121SN1DA
P3V3_AUX                 L20              2        Q_INDUCTOR_SMLF-220/1500MA,INDA
P3V3_AUX                 L26              1        Q_INDUCTOR_SMLF-BLM18EG121SN1DA
P3V3_AUX                 L27              1        Q_INDUCTOR_SMLF-BLM18EG121SN1DA
P3V3_AUX                 L31              2        Q_INDUCTOR_SMLF-BLM15PX121SN1DA
P3V3_AUX                 L34              2        Q_INDUCTOR_SMLF-BLM15PX121SN1DA
P3V3_AUX                 OSC2             4        OSC4_7X25000018-25MHZ,SMLF,MISA
P3V3_AUX                 PC225            1        Q_CAP_0402-0.1UF,25V,10%,X7R,CA
P3V3_AUX                 PC226            1        Q_CAP_C0805-22UF,10V,20%,X6S,CA
P3V3_AUX                 PC227            1        Q_CAP_C0805-22UF,10V,20%,X6S,CA
P3V3_AUX                 PC228            1        Q_CAP_C0805-22UF,10V,20%,X6S,CA
P3V3_AUX                 PC229            1        Q_CAP_C0805-22UF,10V,20%,X6S,CA
P3V3_AUX                 PC239            2        Q_CAP_0402-100PF,50V,5%,NPO,CHA
P3V3_AUX                 PC242            1        Q_CAP_C0805-10UF,25V,10%,X6S,CA
P3V3_AUX                 PC307            1        Q_CAP_C0805-10UF,25V,10%,X6S,CA
P3V3_AUX                 PL35             2        Q_INDUCTOR_SMLF-3.3UH/6A,IND,CA
P3V3_AUX                 PR193            1        Q_RES_0402LF-0,5%,1/16W,CHIP,CA
P3V3_AUX                 PR242            1        Q_RES_0402LF-10K,1%,1/16W,CHIPA
P3V3_AUX                 PR244            1        Q_RES_0402LF-10K,1%,1/16W,CHIPA
P3V3_AUX                 PR255            1        Q_RES_0402LF-10K,1%,1/16W,CHIPA
P3V3_AUX                 PR274            1        Q_RES_0402LF-0,5%,1/16W,CHIP,CA
P3V3_AUX                 PR498            1        Q_RES_0402LF-10K,1%,1/16W,CHIPA
P3V3_AUX                 PR500            1        Q_RES_0402LF-10K,1%,1/16W,CHIPA
P3V3_AUX                 PR534            2        Q_RES_0402LF-56K,1%,1/16W,CHIPA
P3V3_AUX                 PU39             7        RT9059GQW-RT9059GQW,SMLF,IC,ALA
P3V3_AUX                 PU39             8        RT9059GQW-RT9059GQW,SMLF,IC,ALA
P3V3_AUX                 PU39             9        RT9059GQW-RT9059GQW,SMLF,IC,ALA
P3V3_AUX                 PU40             7        RT9059GQW-RT9059GQW,SMLF,IC,ALA
P3V3_AUX                 PU40             8        RT9059GQW-RT9059GQW,SMLF,IC,ALA
P3V3_AUX                 PU40             9        RT9059GQW-RT9059GQW,SMLF,IC,ALA
P3V3_AUX                 Q8               6        MOSFET_DUAL_6P-DMN2400UV-7,SMLA
P3V3_AUX                 R10              1        Q_RES_0402LF-10K,1%,1/16W,CHIPA
P3V3_AUX                 R11              1        Q_RES_0402LF-4.7K,1%,1/16W,CHIA
P3V3_AUX                 R12              1        Q_RES_0402LF-4.7K,5%,1/16W,CHIA
P3V3_AUX                 R13              1        Q_RES_0402LF-4.7K,5%,1/16W,EMPA
P3V3_AUX                 R14              1        Q_RES_0402LF-4.7K,5%,1/16W,EMPA
P3V3_AUX                 R34              1        Q_RES_0402LF-4.7K,5%,1/16W,CHIA
P3V3_AUX                 R38              1        Q_RES_0402LF-4.7K,5%,1/16W,EMPA
P3V3_AUX                 R41              1        Q_RES_0402LF-10K,1%,1/16W,CHIPA
P3V3_AUX                 R42              1        Q_RES_0402LF-10K,1%,1/16W,CHIPA
P3V3_AUX                 R44              1        Q_RES_0402LF-4.7K,5%,1/16W,CHIA
P3V3_AUX                 R45              1        Q_RES_0402LF-4.7K,5%,1/16W,CHIA
P3V3_AUX                 R50              1        Q_RES_0402LF-10K,1%,1/16W,CHIPA
P3V3_AUX                 R55              1        Q_RES_0402LF-4.7K,5%,1/16W,CHIA
P3V3_AUX                 R56              1        Q_RES_0402LF-4.7K,5%,1/16W,CHIA
P3V3_AUX                 R57              1        Q_RES_0402LF-4.7K,5%,1/16W,CHIA
P3V3_AUX                 R58              1        Q_RES_0402LF-4.7K,5%,1/16W,CHIA
P3V3_AUX                 R59              1        Q_RES_0402LF-10K,1%,1/16W,CHIPA
P3V3_AUX                 R61              1        Q_RES_0402LF-4.7K,5%,1/16W,CHIA
P3V3_AUX                 R62              1        Q_RES_0402LF-4.7K,5%,1/16W,CHIA
P3V3_AUX                 R67              1        Q_RES_0402LF-4.7K,1%,1/16W,CHIA
P3V3_AUX                 R68              1        Q_RES_0402LF-4.7K,5%,1/16W,CHIA
P3V3_AUX                 R69              1        Q_RES_0402LF-4.7K,5%,1/16W,CHIA
P3V3_AUX                 R70              1        Q_RES_0402LF-4.7K,5%,1/16W,CHIA
P3V3_AUX                 R72              1        Q_RES_0402LF-4.7K,1%,1/16W,EMPA
P3V3_AUX                 R73              1        Q_RES_0402LF-1K,1%,1/16W,EMPTYA
P3V3_AUX                 R74              1        Q_RES_0402LF-2K,1%,1/16W,CHIP,A
P3V3_AUX                 R75              1        Q_RES_0402LF-2K,1%,1/16W,CHIP,A
P3V3_AUX                 R76              1        Q_RES_0402LF-2K,1%,1/16W,CHIP,A
P3V3_AUX                 R77              1        Q_RES_0402LF-1K,1%,1/16W,EMPTYA
P3V3_AUX                 R78              1        Q_RES_0402LF-2K,1%,1/16W,CHIP,A
P3V3_AUX                 R79              1        Q_RES_0402LF-2K,1%,1/16W,CHIP,A
P3V3_AUX                 R81              1        Q_RES_0402LF-4.7K,5%,1/16W,CHIA
P3V3_AUX                 R82              1        Q_RES_0402LF-2K,1%,1/16W,CHIP,A
P3V3_AUX                 R101             1        Q_RES_0402LF-4.7K,5%,1/16W,CHIA
P3V3_AUX                 R103             1        Q_RES_0402LF-4.7K,5%,1/16W,CHIA
P3V3_AUX                 R105             1        Q_RES_0402LF-10K,1%,1/16W,EMPTA
P3V3_AUX                 R124             1        Q_RES_0402LF-2K,1%,1/16W,CHIP,A
P3V3_AUX                 R140             1        Q_RES_0402LF-4.7K,5%,1/16W,CHIA
P3V3_AUX                 R145             1        Q_RES_0402LF-4.7K,5%,1/16W,CHIA
P3V3_AUX                 R149             1        Q_RES_0402LF-4.7K,5%,1/16W,CHIA
P3V3_AUX                 R155             1        Q_RES_0402LF-0,5%,1/16W,CHIP,CA
P3V3_AUX                 R161             1        Q_RES_0402LF-4.7K,5%,1/16W,CHIA
P3V3_AUX                 R163             1        Q_RES_0402LF-4.7K,5%,1/16W,CHIA
P3V3_AUX                 R167             1        Q_RES_0402LF-330,1%,1/16W,CHIPA
P3V3_AUX                 R169             1        Q_RES_0402LF-4.7K,5%,1/16W,CHIA
P3V3_AUX                 R193             1        Q_RES_0402LF-100K,1%,1/16W,CHIA
P3V3_AUX                 R207             1        Q_RES_0402LF-0,5%,1/16W,CHIP,CA
P3V3_AUX                 R213             1        Q_RES_0402LF-0,5%,1/16W,CHIP,CA
P3V3_AUX                 R226             1        Q_RES_0402LF-10K,0.10%,1/16W,CA
P3V3_AUX                 R227             1        Q_RES_0402LF-10K,0.10%,1/16W,CA
P3V3_AUX                 R230             1        Q_RES_0402LF-10K,0.10%,1/16W,CA
P3V3_AUX                 R231             1        Q_RES_0402LF-0,5%,1/16W,CHIP,CA
P3V3_AUX                 R238             1        Q_RES_0402LF-4.7K,5%,1/16W,CHIA
P3V3_AUX                 R239             1        Q_RES_0402LF-4.7K,5%,1/16W,CHIA
P3V3_AUX                 R240             1        Q_RES_0402LF-4.7K,5%,1/16W,CHIA
P3V3_AUX                 R241             1        Q_RES_0402LF-4.7K,5%,1/16W,CHIA
P3V3_AUX                 R244             1        Q_RES_0402LF-4.7K,5%,1/16W,CHIA
P3V3_AUX                 R245             1        Q_RES_0402LF-4.7K,5%,1/16W,CHIA
P3V3_AUX                 R246             1        Q_RES_0402LF-4.7K,5%,1/16W,CHIA
P3V3_AUX                 R247             1        Q_RES_0402LF-4.7K,5%,1/16W,CHIA
P3V3_AUX                 R248             1        Q_RES_0402LF-4.7K,5%,1/16W,CHIA
P3V3_AUX                 R249             1        Q_RES_0402LF-4.7K,5%,1/16W,CHIA
P3V3_AUX                 R250             1        Q_RES_0402LF-4.7K,5%,1/16W,CHIA
P3V3_AUX                 R251             1        Q_RES_0402LF-4.7K,5%,1/16W,CHIA
P3V3_AUX                 R252             1        Q_RES_0402LF-4.7K,5%,1/16W,CHIA
P3V3_AUX                 R253             1        Q_RES_0402LF-4.7K,5%,1/16W,CHIA
P3V3_AUX                 R254             1        Q_RES_0402LF-4.7K,5%,1/16W,CHIA
P3V3_AUX                 R255             1        Q_RES_0402LF-4.7K,5%,1/16W,CHIA
P3V3_AUX                 R256             1        Q_RES_0402LF-4.7K,5%,1/16W,CHIA
P3V3_AUX                 R257             1        Q_RES_0402LF-4.7K,5%,1/16W,CHIA
P3V3_AUX                 R258             1        Q_RES_0402LF-4.7K,5%,1/16W,CHIA
P3V3_AUX                 R259             1        Q_RES_0402LF-4.7K,5%,1/16W,CHIA
P3V3_AUX                 R260             1        Q_RES_0402LF-4.7K,5%,1/16W,CHIA
P3V3_AUX                 R261             1        Q_RES_0402LF-4.7K,5%,1/16W,CHIA
P3V3_AUX                 R262             1        Q_RES_0402LF-4.7K,5%,1/16W,CHIA
P3V3_AUX                 R264             1        Q_RES_0402LF-4.7K,5%,1/16W,CHIA
P3V3_AUX                 R265             1        Q_RES_0402LF-4.7K,5%,1/16W,CHIA
P3V3_AUX                 R266             1        Q_RES_0402LF-4.7K,5%,1/16W,EMPA
P3V3_AUX                 R267             1        Q_RES_0402LF-4.7K,5%,1/16W,EMPA
P3V3_AUX                 R268             1        Q_RES_0402LF-4.7K,5%,1/16W,CHIA
P3V3_AUX                 R269             1        Q_RES_0402LF-4.7K,5%,1/16W,CHIA
P3V3_AUX                 R274             1        Q_RES_0402LF-100K,1%,1/16W,EMPB
P3V3_AUX                 R287             1        Q_RES_0402LF-499,1%,1/16W,CHIPA
P3V3_AUX                 R289             1        Q_RES_0402LF-10K,1%,1/16W,CHIPA
P3V3_AUX                 R291             1        Q_RES_0402LF-4.7K,1%,1/16W,CHIA
P3V3_AUX                 R295             1        Q_RES_0402LF-10K,1%,1/16W,EMPTA
P3V3_AUX                 R298             1        Q_RES_0402LF-4.7K,1%,1/16W,CHIA
P3V3_AUX                 R299             1        Q_RES_0402LF-4.7K,1%,1/16W,CHIA
P3V3_AUX                 R383             1        Q_RES_0402LF-10K,1%,1/16W,CHIPA
P3V3_AUX                 R387             1        Q_RES_0402LF-4.7K,1%,1/16W,CHIA
P3V3_AUX                 R389             1        Q_RES_0402LF-4.7K,1%,1/16W,CHIA
P3V3_AUX                 R407             1        Q_RES_0402LF-4.7K,5%,1/16W,CHIA
P3V3_AUX                 R414             1        Q_RES_0402LF-4.7K,5%,1/16W,EMPA
P3V3_AUX                 R416             1        Q_RES_0402LF-4.7K,5%,1/16W,CHIA
P3V3_AUX                 R418             1        Q_RES_0402LF-4.7K,5%,1/16W,EMPA
P3V3_AUX                 R422             1        Q_RES_0402LF-4.7K,5%,1/16W,CHIA
P3V3_AUX                 R428             1        Q_RES_0402LF-4.7K,5%,1/16W,CHIA
P3V3_AUX                 R429             1        Q_RES_0402LF-4.7K,5%,1/16W,CHIA
P3V3_AUX                 R430             1        Q_RES_0402LF-4.7K,5%,1/16W,CHIA
P3V3_AUX                 R438             1        Q_RES_0402LF-4.7K,5%,1/16W,CHIA
P3V3_AUX                 R441             1        Q_RES_0402LF-4.7K,5%,1/16W,CHIA
P3V3_AUX                 R446             1        Q_RES_0402LF-4.7K,5%,1/16W,CHIA
P3V3_AUX                 R452             1        Q_RES_0402LF-4.7K,5%,1/16W,CHIA
P3V3_AUX                 R455             1        Q_RES_0402LF-4.7K,5%,1/16W,EMPA
P3V3_AUX                 R464             1        Q_RES_0402LF-10K,1%,1/16W,CHIPA
P3V3_AUX                 R488             1        Q_RES_0402LF-4.7K,1%,1/16W,CHIA
P3V3_AUX                 R490             1        Q_RES_0402LF-4.7K,1%,1/16W,CHIA
P3V3_AUX                 R492             1        Q_RES_0402LF-4.7K,1%,1/16W,CHIA
P3V3_AUX                 R496             1        Q_RES_0402LF-4.7K,1%,1/16W,EMPA
P3V3_AUX                 R497             1        Q_RES_0402LF-10K,1%,1/16W,CHIPA
P3V3_AUX                 R502             1        Q_RES_0402LF-4.7K,1%,1/16W,CHIA
P3V3_AUX                 R504             1        Q_RES_0402LF-8.2K     ,5%  ,1/A
P3V3_AUX                 R508             1        Q_RES_0402LF-10K,1%,1/16W,CHIPA
P3V3_AUX                 R521             1        Q_RES_0402LF-4.7K,5%,1/16W,CHIA
P3V3_AUX                 R555             1        Q_RES_0402LF-4.7K,1%,1/16W,CHIA
P3V3_AUX                 R556             1        Q_RES_0402LF-4.7K,1%,1/16W,EMPA
P3V3_AUX                 R557             1        Q_RES_0402LF-4.7K,1%,1/16W,CHIA
P3V3_AUX                 R558             1        Q_RES_0402LF-4.7K,1%,1/16W,EMPA
P3V3_AUX                 R563             1        Q_RES_0402LF-4.7K,1%,1/16W,CHIA
P3V3_AUX                 R568             1        Q_RES_0402LF-1K,1%,1/16W,CHIP,A
P3V3_AUX                 R569             1        Q_RES_0402LF-1K,1%,1/16W,CHIP,A
P3V3_AUX                 R581             1        Q_RES_0402LF-4.7K,5%,1/16W,CHIA
P3V3_AUX                 R586             1        Q_RES_0402LF-4.7K,5%,1/16W,CHIA
P3V3_AUX                 R587             1        Q_RES_0402LF-4.7K,5%,1/16W,CHIA
P3V3_AUX                 R588             1        Q_RES_0402LF-4.7K,5%,1/16W,CHIA
P3V3_AUX                 R591             1        Q_RES_0402LF-4.7K,5%,1/16W,CHIA
P3V3_AUX                 R592             1        Q_RES_0402LF-4.7K,5%,1/16W,CHIA
P3V3_AUX                 R593             1        Q_RES_0402LF-4.7K,5%,1/16W,CHIA
P3V3_AUX                 R595             1        Q_RES_0402LF-4.7K,5%,1/16W,CHIA
P3V3_AUX                 R596             1        Q_RES_0402LF-4.7K,5%,1/16W,CHIA
P3V3_AUX                 R597             1        Q_RES_0402LF-750,1%,1/16W,CHIPA
P3V3_AUX                 R598             1        Q_RES_0402LF-750,1%,1/16W,CHIPA
P3V3_AUX                 R599             1        Q_RES_0402LF-750,1%,1/16W,CHIPA
P3V3_AUX                 R600             1        Q_RES_0402LF-750,1%,1/16W,CHIPA
P3V3_AUX                 R601             1        Q_RES_0402LF-750,1%,1/16W,CHIPA
P3V3_AUX                 R602             1        Q_RES_0402LF-750,1%,1/16W,CHIPA
P3V3_AUX                 R603             1        Q_RES_0402LF-750,1%,1/16W,CHIPA
P3V3_AUX                 R604             1        Q_RES_0402LF-750,1%,1/16W,CHIPA
P3V3_AUX                 R605             1        Q_RES_0402LF-4.7K,5%,1/16W,CHIA
P3V3_AUX                 R606             1        Q_RES_0402LF-4.7K,5%,1/16W,CHIA
P3V3_AUX                 R607             1        Q_RES_0402LF-4.7K,5%,1/16W,CHIA
P3V3_AUX                 R608             1        Q_RES_0402LF-4.7K,5%,1/16W,CHIA
P3V3_AUX                 R609             1        Q_RES_0402LF-4.7K,5%,1/16W,CHIA
P3V3_AUX                 R610             1        Q_RES_0402LF-4.7K,5%,1/16W,CHIA
P3V3_AUX                 R611             1        Q_RES_0402LF-4.7K,5%,1/16W,CHIA
P3V3_AUX                 R612             1        Q_RES_0402LF-4.7K,5%,1/16W,CHIA
P3V3_AUX                 R613             1        Q_RES_0402LF-4.7K,5%,1/16W,CHIA
P3V3_AUX                 R615             1        Q_RES_0402LF-4.7K,5%,1/16W,CHIA
P3V3_AUX                 R617             1        Q_RES_0402LF-4.7K,5%,1/16W,CHIA
P3V3_AUX                 R619             1        Q_RES_0402LF-4.7K,5%,1/16W,CHIA
P3V3_AUX                 R621             1        Q_RES_0402LF-4.7K,5%,1/16W,CHIA
P3V3_AUX                 R622             1        Q_RES_0402LF-4.7K,5%,1/16W,CHIA
P3V3_AUX                 R624             1        Q_RES_0402LF-4.7K,5%,1/16W,CHIA
P3V3_AUX                 R625             1        Q_RES_0402LF-4.7K,1%,1/16W,CHIA
P3V3_AUX                 R626             1        Q_RES_0402LF-4.7K,5%,1/16W,CHIA
P3V3_AUX                 R627             1        Q_RES_0402LF-4.7K,5%,1/16W,CHIA
P3V3_AUX                 R632             1        Q_RES_0402LF-4.7K,5%,1/16W,CHIA
P3V3_AUX                 R633             1        Q_RES_0402LF-1K,1%,1/16W,EMPTYA
P3V3_AUX                 R640             1        Q_RES_0402LF-4.7K,5%,1/16W,CHIA
P3V3_AUX                 R641             1        Q_RES_0402LF-4.7K,5%,1/16W,CHIA
P3V3_AUX                 R683             1        Q_RES_0402LF-4.7K,5%,1/16W,CHIA
P3V3_AUX                 R692             1        Q_RES_0402LF-4.7K,5%,1/16W,CHIA
P3V3_AUX                 R699             1        Q_RES_0402LF-4.7K,5%,1/16W,EMPA
P3V3_AUX                 R706             1        Q_RES_0402LF-4.7K,5%,1/16W,CHIA
P3V3_AUX                 R710             1        Q_RES_0402LF-100K,1%,1/16W,CHIA
P3V3_AUX                 R716             1        Q_RES_0402LF-10K,1%,1/16W,CHIPA
P3V3_AUX                 R717             1        Q_RES_0402LF-4.7K,5%,1/16W,CHIA
P3V3_AUX                 R768             1        Q_RES_0402LF-8.2K     ,5%  ,1/A
P3V3_AUX                 R774             1        Q_RES_0402LF-4.7K,5%,1/16W,CHIA
P3V3_AUX                 R789             1        Q_RES_0402LF-2.87K,1%,1/16W,CHA
P3V3_AUX                 R806             1        Q_RES_0402LF-4.7K,5%,1/16W,CHIA
P3V3_AUX                 R808             2        Q_RES_0402LF-10K,0.10%,1/16W,CA
P3V3_AUX                 R809             2        Q_RES_0402LF-10K,0.10%,1/16W,CA
P3V3_AUX                 R810             2        Q_RES_0402LF-10K,0.10%,1/16W,CA
P3V3_AUX                 R814             1        Q_RES_0402LF-10K,0.10%,1/16W,CA
P3V3_AUX                 R815             1        Q_RES_0402LF-10K,0.10%,1/16W,CA
P3V3_AUX                 R816             2        Q_RES_0402LF-10,1%,1/16W,CHIP,A
P3V3_AUX                 R821             1        Q_RES_0402LF-4.7K,5%,1/16W,EMPA
P3V3_AUX                 R828             1        Q_RES_0402LF-4.7K,5%,1/16W,CHIA
P3V3_AUX                 R842             1        Q_RES_0402LF-4.7K,5%,1/16W,CHIA
P3V3_AUX                 R843             1        Q_RES_0402LF-4.7K,5%,1/16W,CHIA
P3V3_AUX                 R844             1        Q_RES_0402LF-4.7K,5%,1/16W,CHIA
P3V3_AUX                 R845             1        Q_RES_0402LF-4.7K,5%,1/16W,EMPA
P3V3_AUX                 R846             1        Q_RES_0402LF-4.7K,5%,1/16W,EMPA
P3V3_AUX                 R848             1        Q_RES_0402LF-4.7K,5%,1/16W,CHIA
P3V3_AUX                 R851             1        Q_RES_0402LF-4.7K,5%,1/16W,CHIA
P3V3_AUX                 R870             1        Q_RES_0402LF-4.7K,5%,1/16W,EMPA
P3V3_AUX                 U2               5        SN74LVC1G3157DCKR-SN74LVC1G315A
P3V3_AUX                 U3               5        SN74LVC1G3157DCKR-SN74LVC1G315A
P3V3_AUX                 U4               8        TMP75AIDGKR-TMP75AIDGKR,SMLF,IA
P3V3_AUX                 U5               H15      AST2600A1GP-AST2600A1-GP,SMLF,A
P3V3_AUX                 U5               H16      AST2600A1GP-AST2600A1-GP,SMLF,A
P3V3_AUX                 U5               H17      AST2600A1GP-AST2600A1-GP,SMLF,A
P3V3_AUX                 U5               N22      AST2600A1GP-AST2600A1-GP,SMLF,A
P3V3_AUX                 U5               P22      AST2600A1GP-AST2600A1-GP,SMLF,A
P3V3_AUX                 U5               R22      AST2600A1GP-AST2600A1-GP,SMLF,A
P3V3_AUX                 U5               T22      AST2600A1GP-AST2600A1-GP,SMLF,A
P3V3_AUX                 U5               W16      AST2600A1GP-AST2600A1-GP,SMLF,A
P3V3_AUX                 U5               W17      AST2600A1GP-AST2600A1-GP,SMLF,A
P3V3_AUX                 U5               W18      AST2600A1GP-AST2600A1-GP,SMLF,A
P3V3_AUX                 U5               W19      AST2600A1GP-AST2600A1-GP,SMLF,A
P3V3_AUX                 U6               5        SN74LVC2G07DCKR_SMLF-SN74LVC2GA
P3V3_AUX                 U7               1        BCM54612EB1KMLG-BCM54612EB1KMLA
P3V3_AUX                 U7               4        BCM54612EB1KMLG-BCM54612EB1KMLA
P3V3_AUX                 U7               29       BCM54612EB1KMLG-BCM54612EB1KMLA
P3V3_AUX                 U7               34       BCM54612EB1KMLG-BCM54612EB1KMLA
P3V3_AUX                 U13              5        SN74LVC1G07DCKR-SN74LVC1G07DCKA
P3V3_AUX                 U14              5        AP22811AW57-AP22811AW5-7,SMLF,A
P3V3_AUX                 U15              1        TPS22965DSGR-TPS22965DSGR,SMLFA
P3V3_AUX                 U15              2        TPS22965DSGR-TPS22965DSGR,SMLFA
P3V3_AUX                 U19              8        M24128BWDW6TP-M24128-BWDW6TP,SA
P3V3_AUX                 U20              E6       MTFC8GAKAJCN1MWT-MTFC8GAKAJCN-A
P3V3_AUX                 U20              F5       MTFC8GAKAJCN1MWT-MTFC8GAKAJCN-A
P3V3_AUX                 U20              J10      MTFC8GAKAJCN1MWT-MTFC8GAKAJCN-A
P3V3_AUX                 U20              K9       MTFC8GAKAJCN1MWT-MTFC8GAKAJCN-A
P3V3_AUX                 U21              16       IDTQS3VH257PAG_SMLF-IDTQS3VH25A
P3V3_AUX                 U23              5        SN74LVC1G07DBVR_SMLF-SN74LVC1GA
P3V3_AUX                 U24              5        SN74LVC2G07DCKR_SMLF-SN74LVC2GA
P3V3_AUX                 U25              C6       10M02SCU169C8G-10M02SCU169C8G,A
P3V3_AUX                 U25              C7       10M02SCU169C8G-10M02SCU169C8G,A
P3V3_AUX                 U25              C8       10M02SCU169C8G-10M02SCU169C8G,A
P3V3_AUX                 U25              F2       10M02SCU169C8G-10M02SCU169C8G,A
P3V3_AUX                 U25              F11      10M02SCU169C8G-10M02SCU169C8G,A
P3V3_AUX                 U25              G3       10M02SCU169C8G-10M02SCU169C8G,A
P3V3_AUX                 U25              G11      10M02SCU169C8G-10M02SCU169C8G,A
P3V3_AUX                 U25              H11      10M02SCU169C8G-10M02SCU169C8G,A
P3V3_AUX                 U25              J3       10M02SCU169C8G-10M02SCU169C8G,A
P3V3_AUX                 U25              J11      10M02SCU169C8G-10M02SCU169C8G,A
P3V3_AUX                 U25              K3       10M02SCU169C8G-10M02SCU169C8G,A
P3V3_AUX                 U25              L6       10M02SCU169C8G-10M02SCU169C8G,A
P3V3_AUX                 U25              L7       10M02SCU169C8G-10M02SCU169C8G,A
P3V3_AUX                 U25              L8       10M02SCU169C8G-10M02SCU169C8G,A
P3V3_AUX                 U28              2        MX66L1G45GMI08G-MX66L1G45GMI-0A
P3V3_AUX                 U29              5        74HC1G126GW-74HC1G126GW,SMLF,IA
P3V3_AUX                 U30              16       IDTQS3VH257PAG_SMLF-IDTQS3VH25A
P3V3_AUX                 U31              5        74LVC1G07GW-74LVC1G07GW,SMLF,IA
P3V3_AUX                 U32              5        74LVC1G17GW-74LVC1G17GW,SMLF,IA
P3V3_AUX                 U36              5        74HC1G126GW-74HC1G126GW,SMLF,IA
P3V3_AUX                 U43              6        TPS3808G33DBVR-TPS3808G33DBVR,A
P3V3_AUX_CS              PR276            2        Q_RES_0402LF-8.66K,1%,1/16W,CHA
P3V3_AUX_CS              PU1              4        MPQ8626GDZ-MPQ8626GD-Z,SMLF,ICA
P3V3_AUX_DVDD            R283             1        Q_RES_0402LF-1.5K,1%,1/16W,EMPA
P3V3_AUX_DVDD            R284             1        Q_RES_0402LF-4.7K,1%,1/16W,EMPA
P3V3_AUX_DVDD            R285             1        Q_RES_0402LF-1.5K,1%,1/16W,CHIA
P3V3_AUX_DVDD            R307             1        Q_RES_0402LF-4.7K,1%,1/16W,CHIA
P3V3_AUX_DVDD            R309             1        Q_RES_0402LF-4.7K,1%,1/16W,CHIA
P3V3_AUX_DVDD            R311             1        Q_RES_0402LF-4.7K,1%,1/16W,CHIA
P3V3_AUX_DVDD            R319             1        Q_RES_0402LF-0,5%,1/16W,CHIP,CA
P3V3_AUX_FB_RC           PC239            1        Q_CAP_0402-100PF,50V,5%,NPO,CHA
P3V3_AUX_FB_RC           PR530            2        Q_RES_0402LF-12.4K,1%,1/16W,CHA
P3V3_AUX_FB_RC           PR534            1        Q_RES_0402LF-56K,1%,1/16W,CHIPA
P3V3_AUX_FB_RC           PU1              6        MPQ8626GDZ-MPQ8626GD-Z,SMLF,ICA
P3V3_AUX_MODE            PR532            2        Q_RES_0402LF-60.4K,1%,1/16W,CHA
P3V3_AUX_MODE            PU1              12       MPQ8626GDZ-MPQ8626GD-Z,SMLF,ICA
P3V3_AUX_REF             PC273            1        Q_CAP_0402-3300PF,50V,10%,X7R,A
P3V3_AUX_REF             PU1              8        MPQ8626GDZ-MPQ8626GD-Z,SMLF,ICA
P3V3_AUX_RJ45            C160             1        Q_CAP_0402-0.1UF,25V,10%,X7R,CA
P3V3_AUX_RJ45            C162             1        Q_CAP_C0603-10UF,16V,20%,X6S,CA
P3V3_AUX_RJ45            L20              1        Q_INDUCTOR_SMLF-220/1500MA,INDA
P3V3_AUX_RJ45            R301             1        Q_RES_0402LF-0,5%,1/16W,EMPTY,A
P3V3_AUX_VCC             PC221            1        Q_CAP_C0402-1UF,25V,10%,X6S,CHA
P3V3_AUX_VCC             PU1              13       MPQ8626GDZ-MPQ8626GD-Z,SMLF,ICA
P3V3_AVDD                C293             1        Q_CAP_0402-0.1UF,10V,10%,X7R,TA
P3V3_AVDD                C301             1        Q_CAP_0402-0.1UF,10V,10%,X7R,TA
P3V3_AVDD                C331             1        Q_CAP_0402-0.1UF,10V,10%,X7R,TA
P3V3_AVDD                C348             1        Q_CAP_0402-4.7UF,10V,10%,X5R,CA
P3V3_AVDD                L34              1        Q_INDUCTOR_SMLF-BLM15PX121SN1DA
P3V3_AVDD                U7               16       BCM54612EB1KMLG-BCM54612EB1KMLA
P3V3_AVDD                U7               22       BCM54612EB1KMLG-BCM54612EB1KMLA
P3V3_BIASVDD             C334             1        Q_CAP_0402-0.1UF,10V,10%,X7R,TA
P3V3_BIASVDD             L31              1        Q_INDUCTOR_SMLF-BLM15PX121SN1DA
P3V3_BIASVDD             U7               12       BCM54612EB1KMLG-BCM54612EB1KMLA
P3V3_BMC_USB2AV33        C44              1        Q_CAP_C0402-4.7UF,10V,10%,X5R,A
P3V3_BMC_USB2AV33        C45              1        Q_CAP_0402-0.1UF,25V,10%,X7R,CA
P3V3_BMC_USB2AV33        L4               2        Q_INDUCTOR_SMLF-BLM18PG121SN1DA
P3V3_BMC_USB2AV33        U5               J10      AST2600A1GP-AST2600A1-GP,SMLF,A
P3V3_DP                  C182             1        Q_CAP_C0402-0.1UF,16V,10%,X7R,A
P3V3_DP                  L1               1        Q_FUSE_SMLF-0.5A/6V,IC,DK050TPA
P3V3_DP                  U15              7        TPS22965DSGR-TPS22965DSGR,SMLFA
P3V3_DP                  U15              8        TPS22965DSGR-TPS22965DSGR,SMLFA
P3V3_DP_L                C183             1        Q_CAP_C0603-22UF,10V,20%,X5R,CA
P3V3_DP_L                C184             1        Q_CAP_C0603-22UF,10V,20%,X5R,CA
P3V3_DP_L                J3               20       SCONN20_3VM11207D7307H-SCONN20A
P3V3_DP_L                L1               2        Q_FUSE_SMLF-0.5A/6V,IC,DK050TPA
P3V3_DP_L                U16              5        TPD4E001DBVR-TPD4E001DBVR,SMLFA
P3V3_LED                 C196             1        Q_CAP_0402-0.1UF,25V,10%,X7R,CA
P3V3_LED                 Q12              5        MOSFET_DUAL_6P-2N7002KDW,SMLF,A
P3V3_LED                 R816             1        Q_RES_0402LF-10,1%,1/16W,CHIP,A
P3V3_P1V8_I2C_I3C        C53              1        Q_CAP_C0402-1UF,25V,10%,X6S,CHA
P3V3_P1V8_I2C_I3C        C57              1        Q_CAP_0402-0.1UF,25V,10%,X7R,CA
P3V3_P1V8_I2C_I3C        R231             2        Q_RES_0402LF-0,5%,1/16W,CHIP,CA
P3V3_P1V8_I2C_I3C        R232             2        Q_RES_0402LF-0,5%,1/16W,EMPTY,A
P3V3_P1V8_I2C_I3C        U5               F19      AST2600A1GP-AST2600A1-GP,SMLF,A
P3V3_P1V8_I2C_I3C        U5               F20      AST2600A1GP-AST2600A1-GP,SMLF,A
P3V3_P1V8_SD1VDD         C35              1        Q_CAP_C0402-1UF,25V,10%,X6S,CHA
P3V3_P1V8_SD1VDD         C36              1        Q_CAP_0402-0.1UF,25V,10%,X7R,CA
P3V3_P1V8_SD1VDD         R207             2        Q_RES_0402LF-0,5%,1/16W,CHIP,CA
P3V3_P1V8_SD1VDD         R208             2        Q_RES_0402LF-0,5%,1/16W,EMPTY,A
P3V3_P1V8_SD1VDD         U5               G21      AST2600A1GP-AST2600A1-GP,SMLF,A
P3V3_P1V8_SD1VDD         U5               H21      AST2600A1GP-AST2600A1-GP,SMLF,A
P3V3_P1V8_SD2VDD         C38              1        Q_CAP_C0402-1UF,25V,10%,X6S,CHA
P3V3_P1V8_SD2VDD         C39              1        Q_CAP_0402-0.1UF,25V,10%,X7R,CA
P3V3_P1V8_SD2VDD         R213             2        Q_RES_0402LF-0,5%,1/16W,CHIP,CA
P3V3_P1V8_SD2VDD         R214             2        Q_RES_0402LF-0,5%,1/16W,EMPTY,A
P3V3_P1V8_SD2VDD         U5               H18      AST2600A1GP-AST2600A1-GP,SMLF,A
P3V3_P1V8_SD2VDD         U5               H19      AST2600A1GP-AST2600A1-GP,SMLF,A
P3V3_P2V5_P1V8_RVDD      C30              1        Q_CAP_C0402-1UF,25V,10%,X6S,CHA
P3V3_P2V5_P1V8_RVDD      C31              1        Q_CAP_0402-0.1UF,25V,10%,X7R,CA
P3V3_P2V5_P1V8_RVDD      C32              1        Q_CAP_C0402-1UF,25V,10%,X6S,CHA
P3V3_P2V5_P1V8_RVDD      C33              1        Q_CAP_0402-0.1UF,25V,10%,X7R,CA
P3V3_P2V5_P1V8_RVDD      R154             2        Q_RES_0402LF-0,5%,1/16W,EMPTY,A
P3V3_P2V5_P1V8_RVDD      R155             2        Q_RES_0402LF-0,5%,1/16W,CHIP,CA
P3V3_P2V5_P1V8_RVDD      R156             2        Q_RES_0402LF-0,5%,1/16W,EMPTY,A
P3V3_P2V5_P1V8_RVDD      U5               J21      AST2600A1GP-AST2600A1-GP,SMLF,A
P3V3_P2V5_P1V8_RVDD      U5               K21      AST2600A1GP-AST2600A1-GP,SMLF,A
P3V3_P2V5_P1V8_RVDD      U5               L22      AST2600A1GP-AST2600A1-GP,SMLF,A
P3V3_P2V5_P1V8_RVDD      U5               M22      AST2600A1GP-AST2600A1-GP,SMLF,A
P3V3_PL2303              C187             1        Q_CAP_0402-0.1UF,25V,10%,X7R,CA
P3V3_PL2303              R398             1        Q_RES_0402LF-10K,1%,1/16W,CHIPA
P3V3_PL2303              R401             1        Q_RES_0201LF-1.5K,1%,1/20W,CHIA
P3V3_PL2303              U17              2        FT234XDR-FT234XD-R,SMLF,IC,AL0A
P3V3_PL2303              U17              3        FT234XDR-FT234XD-R,SMLF,IC,AL0A
P3V3_PL2303              U17              9        FT234XDR-FT234XD-R,SMLF,IC,AL0A
P3V3_RGM                 C37              1        Q_CAP_0402-0.1UF,25V,10%,X7R,CA
P3V3_RGM                 C85              1        Q_CAP_0402-0.1UF,25V,10%,X7R,CA
P3V3_RGM                 C251             1        Q_CAP_C0402-0.1UF,16V,10%,X7R,A
P3V3_RGM                 OSC1             4        OSC4_7X25000018-25MHZ,SMLF,MISA
P3V3_RGM                 R31              1        Q_RES_0402LF-4.7K,1%,1/16W,CHIA
P3V3_RGM                 R32              1        Q_RES_0402LF-4.7K,1%,1/16W,CHIA
P3V3_RGM                 R86              1        Q_RES_0402LF-0,5%,1/16W,CHIP,CA
P3V3_RGM                 R203             1        Q_RES_0402LF-10K,0.10%,1/16W,CA
P3V3_RGM                 R204             1        Q_RES_0402LF-10K,0.10%,1/16W,CA
P3V3_RGM                 R211             1        Q_RES_0402LF-10K,1%,1/16W,CHIPA
P3V3_RGM                 R212             1        Q_RES_0402LF-4.7K,5%,1/16W,CHIA
P3V3_RGM                 R523             1        Q_RES_0402LF-10K,0.10%,1/16W,CA
P3V3_RGM                 R559             1        Q_RES_0402LF-4.7K,1%,1/16W,CHIA
P3V3_RGM                 R560             1        Q_RES_0402LF-4.7K,1%,1/16W,EMPA
P3V3_RGM                 R623             1        Q_RES_0402LF-4.7K,1%,1/16W,CHIA
P3V3_RGM                 R709             1        Q_RES_0402LF-10K,1%,1/16W,CHIPA
P3V3_RGM                 U5               K11      AST2600A1GP-AST2600A1-GP,SMLF,A
P3V3_RGM                 U5               K12      AST2600A1GP-AST2600A1-GP,SMLF,A
P3V3_RGM                 U14              1        AP22811AW57-AP22811AW5-7,SMLF,A
P3V3_RTC_AUX             C83              1        Q_CAP_0402-0.1UF,25V,10%,X7R,CA
P3V3_RTC_AUX             U5               V23      AST2600A1GP-AST2600A1-GP,SMLF,A
P3V3_SENSOR              C299             1        Q_CAP_0402-0.1UF,25V,10%,X7R,CA
P3V3_SENSOR              R789             2        Q_RES_0402LF-2.87K,1%,1/16W,CHA
P3V3_SENSOR              R790             1        Q_RES_0402LF-2K,1%,1/16W,CHIP,A
P3V3_SENSOR              U5               AE19     AST2600A1GP-AST2600A1-GP,SMLF,A
P3V3_STBY_DACAV33        C48              1        Q_CAP_C0402-1UF,25V,10%,X6S,CHA
P3V3_STBY_DACAV33        C51              1        Q_CAP_0402-0.1UF,25V,10%,X7R,CA
P3V3_STBY_DACAV33        L7               2        Q_INDUCTOR_SMLF-BLM18PG121SN1DA
P3V3_STBY_DACAV33        U5               V21      AST2600A1GP-AST2600A1-GP,SMLF,A
P3V3_STBY_DACAV33        U5               W21      AST2600A1GP-AST2600A1-GP,SMLF,A
P3V3_STBY_PLLAHVDD       C60              1        Q_CAP_C0402-1UF,25V,10%,X6S,CHA
P3V3_STBY_PLLAHVDD       C65              1        Q_CAP_0402-0.1UF,25V,10%,X7R,CA
P3V3_STBY_PLLAHVDD       L2               2        Q_INDUCTOR_SMLF-BLM18PG121SN1DB
P3V3_STBY_PLLAHVDD       L9               2        Q_INDUCTOR_SMLF-BLM18PG121SN1DA
P3V3_STBY_PLLAHVDD       U5               H14      AST2600A1GP-AST2600A1-GP,SMLF,A
P3V3_XTALVDD             C288             1        Q_CAP_0402-0.1UF,10V,10%,X7R,TA
P3V3_XTALVDD             L18              1        Q_INDUCTOR_SMLF-BLM15PX121SN1DA
P3V3_XTALVDD             U7               9        BCM54612EB1KMLG-BCM54612EB1KMLA
P3V_BAT_R                C174             1        Q_CAP_0402-0.1UF,25V,10%,X7R,CA
P3V_BAT_R                GF1              B41      FCONN168_ME1016810106011-FCONNA
P3V_BAT_R                R777             1        Q_RES_0402LF-200K,1%,1/16W,CHIA
P3V_BAT_R1               Q11              D        MOSFET_N_GSD-NX7002AK,SMLF,IC,A
P3V_BAT_R1               R777             2        Q_RES_0402LF-200K,1%,1/16W,CHIA
P3V_BAT_SENSOR           C275             1        Q_CAP_0402-100PF,50V,5%,NPO,CHA
P3V_BAT_SENSOR           Q11              S        MOSFET_N_GSD-NX7002AK,SMLF,IC,A
P3V_BAT_SENSOR           R778             1        Q_RES_0402LF-100K,1%,1/16W,CHIA
P3V_BAT_SENSOR           U5               AE18     AST2600A1GP-AST2600A1-GP,SMLF,A
P5V_AUX                  C171             1        Q_CAP_C0805-22UF,16V,20%,X6S,CA
P5V_AUX                  C172             1        Q_CAP_0402-470PF,50V,10%,X7R,TA
P5V_AUX                  C202             1        Q_CAP_0402-0.1UF,25V,10%,X7R,CA
P5V_AUX                  C203             1        Q_CAP_0402-0.1UF,25V,10%,X7R,CA
P5V_AUX                  D9               A        SCHOTTKY_AC-SS0530,SMLF,EMPTY,A
P5V_AUX                  D11              A        SCHOTTKY_AC-SS0530,SMLF,IC,BCSA
P5V_AUX                  PC212            1        Q_CAP_0402-0.1UF,25V,10%,X7R,CA
P5V_AUX                  PC213            1        Q_CAP_C0805-22UF,16V,20%,X6S,CA
P5V_AUX                  PC214            1        Q_CAP_C0805-22UF,16V,20%,X6S,CA
P5V_AUX                  PC215            1        Q_CAP_C0805-22UF,16V,20%,X6S,CA
P5V_AUX                  PC217            1        Q_CAP_C0805-22UF,16V,20%,X6S,CA
P5V_AUX                  PC233            1        Q_CAP_C0402-1UF,25V,10%,X6S,CHA
P5V_AUX                  PC243            1        Q_CAP_C0402-1UF,25V,10%,X6S,CHA
P5V_AUX                  PC272            2        Q_CAP_C0402-68PF,50V,5%,COG,CHA
P5V_AUX                  PL34             2        Q_INDUCTOR_SMLF-4.7UH,IND,CV-4A
P5V_AUX                  PR205            1        Q_RES_0402LF-0,5%,1/16W,EMPTY,A
P5V_AUX                  PR275            1        Q_RES_0402LF-0,5%,1/16W,EMPTY,A
P5V_AUX                  PR527            2        Q_RES_0402LF-91K,1%,1/16W,CHIPA
P5V_AUX                  PU39             10       RT9059GQW-RT9059GQW,SMLF,IC,ALA
P5V_AUX                  PU40             10       RT9059GQW-RT9059GQW,SMLF,IC,ALA
P5V_AUX                  R18              1        Q_RES_0402LF-0,5%,1/16W,CHIP,CA
P5V_AUX                  R27              1        Q_RES_0603-0,5%,1/10W,EMPTY,TMA
P5V_AUX                  R376             1        Q_RES_0402LF-4.7K,1%,1/16W,CHIA
P5V_AUX                  R715             1        Q_RES_0402LF-10K,1%,1/16W,CHIPA
P5V_AUX                  R787             1        Q_RES_0402LF-5.36K,1%,1/16W,CHA
P5V_AUX                  U10              1        TPS2553DBVR1-TPS2553DBVR-1,SMLA
P5V_AUX_CS               PR525            1        Q_RES_0402LF-13.3K,1%,1/16W,CHA
P5V_AUX_CS               PU38             3        MPQ8633AGLEC807Z-MPQ8633AGLE-CA
P5V_AUX_FB               PC272            1        Q_CAP_C0402-68PF,50V,5%,COG,CHA
P5V_AUX_FB               PR526            1        Q_RES_0402LF-12.4K,1%,1/16W,CHA
P5V_AUX_FB               PR527            1        Q_RES_0402LF-91K,1%,1/16W,CHIPA
P5V_AUX_FB               PU38             7        MPQ8633AGLEC807Z-MPQ8633AGLE-CA
P5V_AUX_REF              PC271            1        Q_CAP_0402-0.1UF,25V,10%,X7R,CA
P5V_AUX_REF              PU38             5        MPQ8633AGLEC807Z-MPQ8633AGLE-CA
P5V_AUX_VBUS             J4               1        SCONN5_2UB2141000111F-SCONN5_2A
P5V_AUX_VBUS             R406             2        Q_RES_0402LF-0,5%,1/16W,CHIP,CA
P5V_AUX_VCC              PC208            1        Q_CAP_C0402-1UF,25V,10%,X6S,CHA
P5V_AUX_VCC              PR241            1        Q_RES_0402LF-51.1K,1%,1/16W,CHA
P5V_AUX_VCC              PU38             19       MPQ8633AGLEC807Z-MPQ8633AGLE-CA
P5V_BUS                  C188             1        Q_CAP_C0603-10UF,16V,20%,X6S,CA
P5V_BUS                  C189             1        Q_CAP_0402-0.1UF,25V,10%,X7R,CA
P5V_BUS                  C190             1        Q_CAP_C0603-10UF,16V,20%,X6S,CA
P5V_BUS                  R406             1        Q_RES_0402LF-0,5%,1/16W,CHIP,CA
P5V_BUS                  U17              4        FT234XDR-FT234XD-R,SMLF,IC,AL0A
P5V_SENSOR               C295             1        Q_CAP_0402-0.1UF,25V,10%,X7R,CA
P5V_SENSOR               R787             2        Q_RES_0402LF-5.36K,1%,1/16W,CHA
P5V_SENSOR               R788             1        Q_RES_0402LF-2K,1%,1/16W,CHIP,A
P5V_SENSOR               U5               AC18     AST2600A1GP-AST2600A1-GP,SMLF,A
P5V_USB_REAR             C177             1        Q_CAP_1206-47UF ,10V,20%,X5R,CA
P5V_USB_REAR             C178             1        Q_CAP_0402-470PF,50V,10%,X7R,TA
P5V_USB_REAR             C179             1        Q_CAP_0402-470PF,50V,10%,X7R,TA
P5V_USB_REAR             C327             1        Q_CAP_1206-47UF ,10V,20%,X5R,CA
P5V_USB_REAR             J2               1        CONN9_GSB311131HR-CONN9_GSB311A
P5V_USB_REAR             U10              6        TPS2553DBVR1-TPS2553DBVR-1,SMLA
P5V_USB_REAR             U38              4        PRTR5V0U2X-PRTR5V0U2X,SMLF,IC,A
PCIE_BMC_RX_C_DN         C25              2        Q_CAP_0402-0.1UF,25V,10%,X7R,CA
PCIE_BMC_RX_C_DN         GF1              A19      FCONN168_ME1016810106011-FCONNA
PCIE_BMC_RX_C_DP         C24              2        Q_CAP_0402-0.1UF,25V,10%,X7R,CA
PCIE_BMC_RX_C_DP         GF1              A18      FCONN168_ME1016810106011-FCONNA
PCIE_BMC_TX_DN           GF1              A16      FCONN168_ME1016810106011-FCONNA
PCIE_BMC_TX_DN           U5               AF6      AST2600A1GP-AST2600A1-GP,SMLF,A
PCIE_BMC_TX_DP           GF1              A15      FCONN168_ME1016810106011-FCONNA
PCIE_BMC_TX_DP           U5               AF5      AST2600A1GP-AST2600A1-GP,SMLF,A
PD_BIOS_MUX_EN_N         R405             2        Q_RES_0402LF-33       ,1%  ,1/A
PD_BIOS_MUX_EN_N         R467             1        Q_RES_0402LF-2K,1%,1/16W,CHIP,A
PD_BIOS_MUX_EN_N         R870             2        Q_RES_0402LF-4.7K,5%,1/16W,EMPA
PD_BIOS_MUX_EN_N         U21              15       IDTQS3VH257PAG_SMLF-IDTQS3VH25A
PD_BIOS_MUX_EN_N         U30              15       IDTQS3VH257PAG_SMLF-IDTQS3VH25A
PD_BIOS_MUX_EN_R_N       R405             1        Q_RES_0402LF-33       ,1%  ,1/A
PD_BIOS_MUX_EN_R_N       U5               E16      AST2600A1GP-AST2600A1-GP,SMLF,A
PD_BMC_DEBUG             R506             1        Q_RES_0402LF-100,1%,1/16W,CHIPA
PD_BMC_DEBUG             SW3              1        SW4S_DHNF02FTVTR-SW4S_DHNF-02FA
PD_BMC_DISABLE           R431             1        Q_RES_0402LF-100,1%,1/16W,CHIPA
PD_BMC_DISABLE           SW1              1        SW4S_DHNF02FTVTR-SW4S_DHNF-02FA
PD_FPGA_CONFIG_SEL       R811             1        Q_RES_0402LF-10K,0.10%,1/16W,CA
PD_FPGA_CONFIG_SEL       U25              D7       10M02SCU169C8G-10M02SCU169C8G,A
PD_FRU_WC_N              R15              1        Q_RES_0402LF-1K,1%,1/16W,CHIP,A
PD_FRU_WC_N              U19              7        M24128BWDW6TP-M24128-BWDW6TP,SA
PD_INTRUDER_BMC_N        R220             1        Q_RES_0402LF-0,5%,1/16W,CHIP,CA
PD_INTRUDER_BMC_N        U5               AB21     AST2600A1GP-AST2600A1-GP,SMLF,A
PD_JTAGEN                R507             1        Q_RES_0402LF-100,1%,1/16W,CHIPA
PD_JTAGEN                SW3              2        SW4S_DHNF02FTVTR-SW4S_DHNF-02FA
PD_M_BMC_DDR4_PAR        R4               1        Q_RES_0402LF-1K,1%,1/16W,CHIP,A
PD_M_BMC_DDR4_PAR        U1               T3       K4A8G165WCBCTD-K4A8G165WC-BCTDA
PD_M_BMC_DDR4_TEN        R5               1        Q_RES_0402LF-1K,1%,1/16W,CHIP,A
PD_M_BMC_DDR4_TEN        U1               N9       K4A8G165WCBCTD-K4A8G165WC-BCTDA
PD_M_BMC_DDR4_ZQ         R6               1        Q_RES_0402LF-240,1%,1/16W,CHIPA
PD_M_BMC_DDR4_ZQ         U1               F9       K4A8G165WCBCTD-K4A8G165WC-BCTDA
PD_SPI_BMC_BOOT_MOSI     R94              1        Q_RES_0402LF-100,1%,1/16W,CHIPA
PD_SPI_BMC_BOOT_MOSI     SW2              1        SW4S_DHNF02FTVTR-SW4S_DHNF-02FA
PD_SP_ENTEST             R210             2        Q_RES_0402LF-10K,1%,1/16W,CHIPA
PD_SP_ENTEST             U5               C10      AST2600A1GP-AST2600A1-GP,SMLF,A
PECI_BMC                 GF1              B27      FCONN168_ME1016810106011-FCONNA
PECI_BMC                 R209             1        Q_RES_0402LF-10K,1%,1/16W,CHIPA
PECI_BMC                 R216             2        Q_RES_0402LF-0,5%,1/16W,CHIP,CA
PECI_BMC_R               R216             1        Q_RES_0402LF-0,5%,1/16W,CHIP,CA
PECI_BMC_R               U5               AF16     AST2600A1GP-AST2600A1-GP,SMLF,A
PGPPA_BMC_AUX            C96              1        Q_CAP_0402-0.1UF,25V,10%,X7R,CA
PGPPA_BMC_AUX            C224             1        Q_CAP_C0402-10UF,10V,20%,X5R,CA
PGPPA_BMC_AUX            L17              2        Q_INDUCTOR_SMLF-BLM18EG121SN1DA
PGPPA_BMC_AUX            R115             1        Q_RES_0402LF-4.7K,5%,1/16W,CHIA
PGPPA_BMC_AUX            R116             1        Q_RES_0402LF-4.7K,5%,1/16W,CHIA
PGPPA_BMC_AUX            R117             1        Q_RES_0402LF-4.7K,5%,1/16W,CHIA
PGPPA_BMC_AUX            R797             1        Q_RES_0402LF-2.87K,1%,1/16W,CHA
PGPPA_BMC_AUX            U5               W15      AST2600A1GP-AST2600A1-GP,SMLF,A
PGPPA_BMC_AUX_L          L17              1        Q_INDUCTOR_SMLF-BLM18EG121SN1DA
PGPPA_BMC_AUX_L          Q8               1        MOSFET_DUAL_6P-DMN2400UV-7,SMLA
PGPPA_BMC_AUX_L          Q8               4        MOSFET_DUAL_6P-DMN2400UV-7,SMLA
PGPPA_BMC_AUX_SENSOR     C314             1        Q_CAP_0402-0.1UF,25V,10%,X7R,CA
PGPPA_BMC_AUX_SENSOR     R797             2        Q_RES_0402LF-2.87K,1%,1/16W,CHA
PGPPA_BMC_AUX_SENSOR     R798             1        Q_RES_0402LF-2K,1%,1/16W,CHIP,A
PGPPA_BMC_AUX_SENSOR     U5               AB19     AST2600A1GP-AST2600A1-GP,SMLF,A
PHYA0                    R455             2        Q_RES_0402LF-4.7K,5%,1/16W,EMPA
PHYA0                    U7               41       BCM54612EB1KMLG-BCM54612EB1KMLA
PHY_CT                   C163             1        Q_CAP_C0402-0.01UF,50V,10%,X7RA
PHY_CT                   C164             1        Q_CAP_C0402-0.01UF,50V,10%,X7RA
PHY_CT                   J1               R5       SCONN14_RS6QU0001-SCONN14_RS6-A
PHY_CT                   J1               R6       SCONN14_RS6QU0001-SCONN14_RS6-A
PHY_LED1                 C166             1        Q_CAP_0402-100PF,50V,5%,NPO,CHA
PHY_LED1                 R305             1        Q_RES_0402LF-220,5%,1/16W,CHIPA
PHY_LED1                 R307             2        Q_RES_0402LF-4.7K,1%,1/16W,CHIA
PHY_LED1                 R308             1        Q_RES_0402LF-4.7K,1%,1/16W,EMPA
PHY_LED1                 U7               45       BCM54612EB1KMLG-BCM54612EB1KMLA
PHY_LED2                 C167             1        Q_CAP_0402-100PF,50V,5%,NPO,CHA
PHY_LED2                 R306             1        Q_RES_0402LF-220,5%,1/16W,CHIPA
PHY_LED2                 R309             2        Q_RES_0402LF-4.7K,1%,1/16W,CHIA
PHY_LED2                 R310             1        Q_RES_0402LF-4.7K,1%,1/16W,EMPA
PHY_LED2                 U7               44       BCM54612EB1KMLG-BCM54612EB1KMLA
PHY_LED3                 C165             1        Q_CAP_0402-100PF,50V,5%,NPO,CHA
PHY_LED3                 R304             1        Q_RES_0402LF-220,5%,1/16W,CHIPA
PHY_LED3                 R311             2        Q_RES_0402LF-4.7K,1%,1/16W,CHIA
PHY_LED3                 R312             1        Q_RES_0402LF-4.7K,1%,1/16W,EMPA
PHY_LED3                 U7               43       BCM54612EB1KMLG-BCM54612EB1KMLA
PHY_RDAC                 R400             1        Q_RES_0402LF-1.24K,1%,1/16W,CHA
PHY_RDAC                 U7               10       BCM54612EB1KMLG-BCM54612EB1KMLA
PHY_TRD_0_N              J1               R2       SCONN14_RS6QU0001-SCONN14_RS6-A
PHY_TRD_0_N              U7               15       BCM54612EB1KMLG-BCM54612EB1KMLA
PHY_TRD_0_N              U8               1        TPD4E001DBVR-TPD4E001DBVR,SMLFB
PHY_TRD_0_P              J1               R1       SCONN14_RS6QU0001-SCONN14_RS6-A
PHY_TRD_0_P              U7               14       BCM54612EB1KMLG-BCM54612EB1KMLA
PHY_TRD_0_P              U8               6        TPD4E001DBVR-TPD4E001DBVR,SMLFB
PHY_TRD_1_N              J1               R4       SCONN14_RS6QU0001-SCONN14_RS6-A
PHY_TRD_1_N              U7               17       BCM54612EB1KMLG-BCM54612EB1KMLA
PHY_TRD_1_N              U8               3        TPD4E001DBVR-TPD4E001DBVR,SMLFB
PHY_TRD_1_P              J1               R3       SCONN14_RS6QU0001-SCONN14_RS6-A
PHY_TRD_1_P              U7               18       BCM54612EB1KMLG-BCM54612EB1KMLA
PHY_TRD_1_P              U8               4        TPD4E001DBVR-TPD4E001DBVR,SMLFB
PHY_TRD_2_N              J1               R8       SCONN14_RS6QU0001-SCONN14_RS6-A
PHY_TRD_2_N              U7               21       BCM54612EB1KMLG-BCM54612EB1KMLA
PHY_TRD_2_N              U9               1        TPD4E001DBVR-TPD4E001DBVR,SMLFB
PHY_TRD_2_P              J1               R7       SCONN14_RS6QU0001-SCONN14_RS6-A
PHY_TRD_2_P              U7               20       BCM54612EB1KMLG-BCM54612EB1KMLA
PHY_TRD_2_P              U9               6        TPD4E001DBVR-TPD4E001DBVR,SMLFB
PHY_TRD_3_N              J1               R10      SCONN14_RS6QU0001-SCONN14_RS6-A
PHY_TRD_3_N              U7               23       BCM54612EB1KMLG-BCM54612EB1KMLA
PHY_TRD_3_N              U9               3        TPD4E001DBVR-TPD4E001DBVR,SMLFB
PHY_TRD_3_P              J1               R9       SCONN14_RS6QU0001-SCONN14_RS6-A
PHY_TRD_3_P              U7               24       BCM54612EB1KMLG-BCM54612EB1KMLA
PHY_TRD_3_P              U9               4        TPD4E001DBVR-TPD4E001DBVR,SMLFB
PU39_ADJ                 PU39             4        RT9059GQW-RT9059GQW,SMLF,IC,ALA
PU39_ADJ                 R829             2        Q_RES_0402LF-25.5K,1%,1/16W,CHA
PU39_ADJ                 R830             1        Q_RES_0402LF-12K,1%,1/16W,CHIPA
PU40_ADJ                 PU40             4        RT9059GQW-RT9059GQW,SMLF,IC,ALA
PU40_ADJ                 R831             2        Q_RES_0402LF-15K,1%,1/16W,CHIPA
PU40_ADJ                 R832             1        Q_RES_0402LF-12K,1%,1/16W,CHIPA
PU_25M_BMC_CLK_EN        OSC1             1        OSC4_7X25000018-25MHZ,SMLF,MISA
PU_25M_BMC_CLK_EN        R212             2        Q_RES_0402LF-4.7K,5%,1/16W,CHIA
PU_25M_FPGA_CLK_EN       OSC2             1        OSC4_7X25000018-25MHZ,SMLF,MISA
PU_25M_FPGA_CLK_EN       R806             2        Q_RES_0402LF-4.7K,5%,1/16W,CHIA
PU_BMC_FWSPIABR_N        R239             2        Q_RES_0402LF-4.7K,5%,1/16W,CHIA
PU_BMC_FWSPIABR_N        U5               AC12     AST2600A1GP-AST2600A1-GP,SMLF,A
PU_FPGA_CONFIG_DONE      R808             1        Q_RES_0402LF-10K,0.10%,1/16W,CA
PU_FPGA_CONFIG_DONE      U25              C5       10M02SCU169C8G-10M02SCU169C8G,A
PU_FPGA_NCONFIG          R809             1        Q_RES_0402LF-10K,0.10%,1/16W,CA
PU_FPGA_NCONFIG          U25              E7       10M02SCU169C8G-10M02SCU169C8G,A
PU_FPGA_NSTATUS          R810             1        Q_RES_0402LF-10K,0.10%,1/16W,CA
PU_FPGA_NSTATUS          U25              C4       10M02SCU169C8G-10M02SCU169C8G,A
PU_FWSPIWP_N             R240             2        Q_RES_0402LF-4.7K,5%,1/16W,CHIA
PU_FWSPIWP_N             U5               AB12     AST2600A1GP-AST2600A1-GP,SMLF,A
PU_JTAG_TCK_MUX          R615             2        Q_RES_0402LF-4.7K,5%,1/16W,CHIA
PU_JTAG_TCK_MUX          SW1              2        SW4S_DHNF02FTVTR-SW4S_DHNF-02FA
PU_LED_ACT               J1               L4       SCONN14_RS6QU0001-SCONN14_RS6-A
PU_LED_ACT               R319             2        Q_RES_0402LF-0,5%,1/16W,CHIP,CA
PU_LED_POSTCODE_0_N      D0               A        Q_LED_SMLF-LED_GREEN,19-213/GVA
PU_LED_POSTCODE_0_N      R604             2        Q_RES_0402LF-750,1%,1/16W,CHIPA
PU_LED_POSTCODE_1_N      D1               A        Q_LED_SMLF-LED_GREEN,19-213/GVA
PU_LED_POSTCODE_1_N      R603             2        Q_RES_0402LF-750,1%,1/16W,CHIPA
PU_LED_POSTCODE_2_N      D2               A        Q_LED_SMLF-LED_GREEN,19-213/GVA
PU_LED_POSTCODE_2_N      R602             2        Q_RES_0402LF-750,1%,1/16W,CHIPA
PU_LED_POSTCODE_3_N      D3               A        Q_LED_SMLF-LED_GREEN,19-213/GVA
PU_LED_POSTCODE_3_N      R601             2        Q_RES_0402LF-750,1%,1/16W,CHIPA
PU_LED_POSTCODE_4_N      D4               A        Q_LED_SMLF-LED_RED,19-217/R6C-A
PU_LED_POSTCODE_4_N      R600             2        Q_RES_0402LF-750,1%,1/16W,CHIPA
PU_LED_POSTCODE_5_N      D5               A        Q_LED_SMLF-LED_RED,19-217/R6C-A
PU_LED_POSTCODE_5_N      R599             2        Q_RES_0402LF-750,1%,1/16W,CHIPA
PU_LED_POSTCODE_6_N      D6               A        Q_LED_SMLF-LED_RED,19-217/R6C-A
PU_LED_POSTCODE_6_N      R598             2        Q_RES_0402LF-750,1%,1/16W,CHIPA
PU_LED_POSTCODE_7_N      D7               A        Q_LED_SMLF-LED_RED,19-217/R6C-A
PU_LED_POSTCODE_7_N      R597             2        Q_RES_0402LF-750,1%,1/16W,CHIPA
PU_LOADSW_EN             R389             2        Q_RES_0402LF-4.7K,1%,1/16W,CHIA
PU_LOADSW_EN             R390             1        Q_RES_0402LF-4.7K,1%,1/16W,EMPA
PU_LOADSW_EN             U15              3        TPS22965DSGR-TPS22965DSGR,SMLFA
PU_RJ45_ESD              R301             2        Q_RES_0402LF-0,5%,1/16W,EMPTY,A
PU_RJ45_ESD              U8               5        TPD4E001DBVR-TPD4E001DBVR,SMLFB
PU_RJ45_ESD              U9               5        TPD4E001DBVR-TPD4E001DBVR,SMLFB
PU_SPI1ABR               R241             2        Q_RES_0402LF-4.7K,5%,1/16W,CHIA
PU_SPI1ABR               U5               AD10     AST2600A1GP-AST2600A1-GP,SMLF,A
PU_SPI1WP_N              R683             2        Q_RES_0402LF-4.7K,5%,1/16W,CHIA
PU_SPI1WP_N              U5               AE10     AST2600A1GP-AST2600A1-GP,SMLF,A
PU_SPI_BMC_BOOT_MISO     R70              2        Q_RES_0402LF-4.7K,5%,1/16W,CHIA
PU_SPI_BMC_BOOT_MISO     SW2              2        SW4S_DHNF02FTVTR-SW4S_DHNF-02FA
PVCC1_AUX                PR274            2        Q_RES_0402LF-0,5%,1/16W,CHIP,CA
PVCC1_AUX                PR275            2        Q_RES_0402LF-0,5%,1/16W,EMPTY,A
PVCC1_AUX                PR539            1        Q_RES_0402LF-5.1,5%,1/16W,CHIPA
PVCC2_AUX                PR193            2        Q_RES_0402LF-0,5%,1/16W,CHIP,CA
PVCC2_AUX                PR205            2        Q_RES_0402LF-0,5%,1/16W,EMPTY,A
PVCC2_AUX                PR541            1        Q_RES_0402LF-5.1,5%,1/16W,CHIPA
PVCCA_AUX_PLD            C193             1        Q_CAP_0402-2.2UF,10V,20%,X5R,TA
PVCCA_AUX_PLD            C194             1        Q_CAP_0402-0.1UF,25V,10%,X7R,CA
PVCCA_AUX_PLD            C195             1        Q_CAP_0402-0.1UF,25V,10%,X7R,CA
PVCCA_AUX_PLD            C339             1        Q_CAP_0402-0.1UF,25V,10%,X7R,CA
PVCCA_AUX_PLD            C340             1        Q_CAP_0402-0.1UF,25V,10%,X7R,CA
PVCCA_AUX_PLD            C341             1        Q_CAP_0402-0.1UF,25V,10%,X7R,CA
PVCCA_AUX_PLD            C342             1        Q_CAP_0402-0.1UF,25V,10%,X7R,CA
PVCCA_AUX_PLD            C343             1        Q_CAP_0402-0.1UF,25V,10%,X7R,CA
PVCCA_AUX_PLD            C344             1        Q_CAP_0402-0.1UF,25V,10%,X7R,CA
PVCCA_AUX_PLD            C345             1        Q_CAP_0402-0.1UF,25V,10%,X7R,CA
PVCCA_AUX_PLD            L27              2        Q_INDUCTOR_SMLF-BLM18EG121SN1DA
PVCCA_AUX_PLD            U25              F7       10M02SCU169C8G-10M02SCU169C8G,A
PVCCA_AUX_PLD            U25              G6       10M02SCU169C8G-10M02SCU169C8G,A
PVCCA_AUX_PLD            U25              G8       10M02SCU169C8G-10M02SCU169C8G,A
PVCCA_AUX_PLD            U25              H7       10M02SCU169C8G-10M02SCU169C8G,A
PVCCD_PLL_AUX            C220             1        Q_CAP_0402-0.1UF,25V,10%,X7R,CA
PVCCD_PLL_AUX            C272             1        Q_CAP_0402-2.2UF,10V,20%,X5R,TA
PVCCD_PLL_AUX            C281             1        Q_CAP_0402-0.1UF,25V,10%,X7R,CA
PVCCD_PLL_AUX            C287             1        Q_CAP_0402-0.1UF,25V,10%,X7R,CA
PVCCD_PLL_AUX            L26              2        Q_INDUCTOR_SMLF-BLM18EG121SN1DA
PVCCD_PLL_AUX            U25              D4       10M02SCU169C8G-10M02SCU169C8G,A
PVCCD_PLL_AUX            U25              D10      10M02SCU169C8G-10M02SCU169C8G,A
PVCCD_PLL_AUX            U25              K4       10M02SCU169C8G-10M02SCU169C8G,A
PVCCD_PLL_AUX            U25              K9       10M02SCU169C8G-10M02SCU169C8G,A
PVCCIO_PECI_BMC          C42              1        Q_CAP_C0603-22UF,6.3V,20%,X6S,A
PVCCIO_PECI_BMC          C43              1        Q_CAP_C0402-1UF,25V,10%,X6S,CHA
PVCCIO_PECI_BMC          GF1              B28      FCONN168_ME1016810106011-FCONNA
PVCCIO_PECI_BMC          U5               AA18     AST2600A1GP-AST2600A1-GP,SMLF,A
PWRGD_CPUPWRGD_LVC1      U5               W26      AST2600A1GP-AST2600A1-GP,SMLF,A
PWRGD_CPUPWRGD_LVC1      U25              N6       10M02SCU169C8G-10M02SCU169C8G,A
PWRGD_P1V0_AUX           R49              1        Q_RES_0402LF-0,5%,1/16W,CHIP,CA
PWRGD_P1V0_AUX           R277             2        Q_RES_0402LF-0,5%,1/16W,CHIP,CA
PWRGD_P1V0_AUX           R379             2        Q_RES_0402LF-0,5%,1/16W,CHIP,CA
PWRGD_P1V0_AUX_DELAY     R451             1        Q_RES_0402LF-0,5%,1/16W,CHIP,CA
PWRGD_P1V0_AUX_DELAY     R711             2        Q_RES_0402LF-0,5%,1/16W,EMPTY,A
PWRGD_P1V0_AUX_DELAY     U6               1        SN74LVC2G07DCKR_SMLF-SN74LVC2GA
PWRGD_P1V0_AUX_DELAY_BUF R192             1        Q_RES_0402LF-49.9     ,1%  ,1/A
PWRGD_P1V0_AUX_DELAY_BUF U6               6        SN74LVC2G07DCKR_SMLF-SN74LVC2GA
PWRGD_P1V0_AUX_DELAY_R1  R451             2        Q_RES_0402LF-0,5%,1/16W,CHIP,CA
PWRGD_P1V0_AUX_DELAY_R1  U43              1        TPS3808G33DBVR-TPS3808G33DBVR,A
PWRGD_P1V0_AUX_R         C156             1        Q_CAP_C0402-0.001UF,50V,10%,X7A
PWRGD_P1V0_AUX_R         PR500            2        Q_RES_0402LF-10K,1%,1/16W,CHIPA
PWRGD_P1V0_AUX_R         PU42             13       NB695GDZ-NB695GD-Z,SMLF,IC,AL0A
PWRGD_P1V0_AUX_R         R277             1        Q_RES_0402LF-0,5%,1/16W,CHIP,CA
PWRGD_P1V0_AUX_R1        R379             1        Q_RES_0402LF-0,5%,1/16W,CHIP,CA
PWRGD_P1V0_AUX_R1        U25              B2       10M02SCU169C8G-10M02SCU169C8G,A
PWRGD_P1V0_AUX_R2        R49              2        Q_RES_0402LF-0,5%,1/16W,CHIP,CA
PWRGD_P1V0_AUX_R2        U43              3        TPS3808G33DBVR-TPS3808G33DBVR,A
PWRGD_P1V2_AUX           R276             2        Q_RES_0402LF-0,5%,1/16W,CHIP,CA
PWRGD_P1V2_AUX           R323             2        Q_RES_0402LF-0,5%,1/16W,CHIP,CA
PWRGD_P1V2_AUX           R399             1        Q_RES_0402LF-0,5%,1/16W,CHIP,CA
PWRGD_P1V2_AUX_R         C155             1        Q_CAP_C0402-0.001UF,50V,10%,X7A
PWRGD_P1V2_AUX_R         PR498            2        Q_RES_0402LF-10K,1%,1/16W,CHIPA
PWRGD_P1V2_AUX_R         PU41             13       NB695GDZ-NB695GD-Z,SMLF,IC,AL0A
PWRGD_P1V2_AUX_R         R276             1        Q_RES_0402LF-0,5%,1/16W,CHIP,CA
PWRGD_P1V2_AUX_R1        R323             1        Q_RES_0402LF-0,5%,1/16W,CHIP,CA
PWRGD_P1V2_AUX_R1        U25              A2       10M02SCU169C8G-10M02SCU169C8G,A
PWRGD_P1V2_AUX_R2        PU42             5        NB695GDZ-NB695GD-Z,SMLF,IC,AL0A
PWRGD_P1V2_AUX_R2        R399             2        Q_RES_0402LF-0,5%,1/16W,CHIP,CA
PWRGD_P1V8_AUX           R275             1        Q_RES_0402LF-0,5%,1/16W,CHIP,CA
PWRGD_P1V8_AUX           R321             2        Q_RES_0402LF-0,5%,1/16W,CHIP,CA
PWRGD_P1V8_AUX           R380             1        Q_RES_0402LF-0,5%,1/16W,CHIP,CA
PWRGD_P1V8_AUX           R764             1        Q_RES_0402LF-0,5%,1/16W,EMPTY,A
PWRGD_P1V8_AUX_R         C154             1        Q_CAP_C0402-0.001UF,50V,10%,X7A
PWRGD_P1V8_AUX_R         PR255            2        Q_RES_0402LF-10K,1%,1/16W,CHIPA
PWRGD_P1V8_AUX_R         PU40             5        RT9059GQW-RT9059GQW,SMLF,IC,ALA
PWRGD_P1V8_AUX_R         R275             2        Q_RES_0402LF-0,5%,1/16W,CHIP,CA
PWRGD_P1V8_AUX_R1        R321             1        Q_RES_0402LF-0,5%,1/16W,CHIP,CA
PWRGD_P1V8_AUX_R1        U25              B4       10M02SCU169C8G-10M02SCU169C8G,A
PWRGD_P1V8_AUX_R2        R380             2        Q_RES_0402LF-0,5%,1/16W,CHIP,CA
PWRGD_P1V8_AUX_R2        U14              4        AP22811AW57-AP22811AW5-7,SMLF,A
PWRGD_P2V5_AUX           R35              1        Q_RES_0402LF-0,5%,1/16W,CHIP,CA
PWRGD_P2V5_AUX           R320             2        Q_RES_0402LF-0,5%,1/16W,CHIP,CA
PWRGD_P2V5_AUX           R393             1        Q_RES_0402LF-0,5%,1/16W,CHIP,CA
PWRGD_P2V5_AUX_R         C153             1        Q_CAP_C0402-0.001UF,50V,10%,X7A
PWRGD_P2V5_AUX_R         PR244            2        Q_RES_0402LF-10K,1%,1/16W,CHIPA
PWRGD_P2V5_AUX_R         PU39             5        RT9059GQW-RT9059GQW,SMLF,IC,ALA
PWRGD_P2V5_AUX_R         R35              2        Q_RES_0402LF-0,5%,1/16W,CHIP,CA
PWRGD_P2V5_AUX_R1        R320             1        Q_RES_0402LF-0,5%,1/16W,CHIP,CA
PWRGD_P2V5_AUX_R1        U25              B3       10M02SCU169C8G-10M02SCU169C8G,A
PWRGD_P2V5_AUX_R2        PU40             6        RT9059GQW-RT9059GQW,SMLF,IC,ALA
PWRGD_P2V5_AUX_R2        R393             2        Q_RES_0402LF-0,5%,1/16W,CHIP,CA
PWRGD_P3V3_AUX           R293             2        Q_RES_0402LF-0,5%,1/16W,CHIP,CA
PWRGD_P3V3_AUX           R318             2        Q_RES_0402LF-0,5%,1/16W,CHIP,CA
PWRGD_P3V3_AUX           R382             1        Q_RES_0402LF-0,5%,1/16W,CHIP,CA
PWRGD_P3V3_AUX_R         C151             1        Q_CAP_C0402-0.001UF,50V,10%,X7A
PWRGD_P3V3_AUX_R         PR242            2        Q_RES_0402LF-10K,1%,1/16W,CHIPA
PWRGD_P3V3_AUX_R         PU1              9        MPQ8626GDZ-MPQ8626GD-Z,SMLF,ICA
PWRGD_P3V3_AUX_R         R293             1        Q_RES_0402LF-0,5%,1/16W,CHIP,CA
PWRGD_P3V3_AUX_R1        R318             1        Q_RES_0402LF-0,5%,1/16W,CHIP,CA
PWRGD_P3V3_AUX_R1        U25              E6       10M02SCU169C8G-10M02SCU169C8G,A
PWRGD_P3V3_AUX_R2        PU39             6        RT9059GQW-RT9059GQW,SMLF,IC,ALA
PWRGD_P3V3_AUX_R2        R382             2        Q_RES_0402LF-0,5%,1/16W,CHIP,CA
PWRGD_P3V3_RGM           R99              2        Q_RES_0402LF-0,5%,1/16W,CHIP,CA
PWRGD_P3V3_RGM           R322             2        Q_RES_0402LF-0,5%,1/16W,CHIP,CA
PWRGD_P3V3_RGM           R708             1        Q_RES_0402LF-0,5%,1/16W,CHIP,CA
PWRGD_P3V3_RGM_R         C252             1        Q_CAP_C0402-0.1UF,16V,10%,EMPTA
PWRGD_P3V3_RGM_R         R99              1        Q_RES_0402LF-0,5%,1/16W,CHIP,CA
PWRGD_P3V3_RGM_R         R709             2        Q_RES_0402LF-10K,1%,1/16W,CHIPA
PWRGD_P3V3_RGM_R1        R322             1        Q_RES_0402LF-0,5%,1/16W,CHIP,CA
PWRGD_P3V3_RGM_R1        U25              A5       10M02SCU169C8G-10M02SCU169C8G,A
PWRGD_P5V_AUX            R141             2        Q_RES_0402LF-0,5%,1/16W,CHIP,CA
PWRGD_P5V_AUX            R292             2        Q_RES_0402LF-0,5%,1/16W,CHIP,CA
PWRGD_P5V_AUX            R381             1        Q_RES_0402LF-0,5%,1/16W,CHIP,CA
PWRGD_P5V_AUX_R          C150             1        Q_CAP_C0402-0.001UF,50V,10%,X7A
PWRGD_P5V_AUX_R          PR241            2        Q_RES_0402LF-51.1K,1%,1/16W,CHA
PWRGD_P5V_AUX_R          PR245            1        Q_RES_0402LF-100K,1%,1/16W,CHIA
PWRGD_P5V_AUX_R          PU38             9        MPQ8633AGLEC807Z-MPQ8633AGLE-CA
PWRGD_P5V_AUX_R          R292             1        Q_RES_0402LF-0,5%,1/16W,CHIP,CA
PWRGD_P5V_AUX_R1         R141             1        Q_RES_0402LF-0,5%,1/16W,CHIP,CA
PWRGD_P5V_AUX_R1         U25              A3       10M02SCU169C8G-10M02SCU169C8G,A
PWRGD_P5V_AUX_R2         PU1              5        MPQ8626GDZ-MPQ8626GD-Z,SMLF,ICA
PWRGD_P5V_AUX_R2         R381             2        Q_RES_0402LF-0,5%,1/16W,CHIP,CA
PWRGD_PCH_PWROK          U5               T23      AST2600A1GP-AST2600A1-GP,SMLF,A
PWRGD_PCH_PWROK          U25              G4       10M02SCU169C8G-10M02SCU169C8G,A
PWRGD_PSU_AC_PWROK       R66              2        Q_RES_0402LF-100K,1%,1/16W,CHIA
PWRGD_PSU_AC_PWROK       R243             1        Q_RES_0402LF-33       ,1%  ,1/A
PWRGD_PSU_AC_PWROK       R711             1        Q_RES_0402LF-0,5%,1/16W,EMPTY,A
PWRGD_PSU_AC_PWROK       R836             1        Q_RES_0402LF-33       ,1%  ,1/A
PWRGD_PSU_AC_PWROK       R837             1        Q_RES_0402LF-33       ,1%  ,1/B
PWRGD_PSU_AC_PWROK_BMC   R836             2        Q_RES_0402LF-33       ,1%  ,1/A
PWRGD_PSU_AC_PWROK_BMC   U5               A12      AST2600A1GP-AST2600A1-GP,SMLF,A
PWRGD_PSU_AC_PWROK_PLD   R837             2        Q_RES_0402LF-33       ,1%  ,1/B
PWRGD_PSU_AC_PWROK_PLD   U25              E3       10M02SCU169C8G-10M02SCU169C8G,A
PWRGD_PSU_AC_PWROK_R     GF1              A44      FCONN168_ME1016810106011-FCONNA
PWRGD_PSU_AC_PWROK_R     R243             2        Q_RES_0402LF-33       ,1%  ,1/A
PWRGD_SYS_PWROK          GF1              A48      FCONN168_ME1016810106011-FCONNA
PWRGD_SYS_PWROK          R40              2        Q_RES_0402LF-2K,1%,1/16W,EMPTYA
PWRGD_SYS_PWROK          R840             1        Q_RES_0402LF-33       ,1%  ,1/A
PWRGD_SYS_PWROK          R841             2        Q_RES_0402LF-33       ,1%  ,1/A
PWRGD_SYS_PWROK_BMC      R840             2        Q_RES_0402LF-33       ,1%  ,1/A
PWRGD_SYS_PWROK_BMC      U5               B12      AST2600A1GP-AST2600A1-GP,SMLF,A
PWRGD_SYS_PWROK_PLD      R841             1        Q_RES_0402LF-33       ,1%  ,1/A
PWRGD_SYS_PWROK_PLD      U25              A11      10M02SCU169C8G-10M02SCU169C8G,A
PWR_BTN_BMC_N            R80              2        Q_RES_0402LF-33       ,1%  ,1/B
PWR_BTN_BMC_N            R81              2        Q_RES_0402LF-4.7K,5%,1/16W,CHIA
PWR_BTN_BMC_N            R225             2        Q_RES_0402LF-33       ,1%  ,1/A
PWR_BTN_BMC_N            U25              N4       10M02SCU169C8G-10M02SCU169C8G,A
PWR_BTN_BMC_N            U31              4        74LVC1G07GW-74LVC1G07GW,SMLF,IA
PWR_LED                  Q12              2        MOSFET_DUAL_6P-2N7002KDW,SMLF,A
PWR_LED                  R316             2        Q_RES_0402LF-0,5%,1/16W,CHIP,CA
PWR_LED                  R317             2        Q_RES_0402LF-0,5%,1/16W,CHIP,CA
PWR_LED                  R839             1        Q_RES_0402LF-8.2K     ,5%  ,1/A
PWR_LED_BUF              Q12              6        MOSFET_DUAL_6P-2N7002KDW,SMLF,A
PWR_LED_BUF              R812             1        Q_RES_0402LF-33       ,1%  ,1/A
PWR_LED_BUF_R            C326             1        Q_CAP_0402-470PF,50V,10%,X7R,TA
PWR_LED_BUF_R            D14              C        Q_LED_SMLF-LED_BLUE,12-215/BHCA
PWR_LED_BUF_R            R812             2        Q_RES_0402LF-33       ,1%  ,1/A
PWR_LED_BUF_R            R814             2        Q_RES_0402LF-10K,0.10%,1/16W,CA
PWR_LED_CPLD             R317             1        Q_RES_0402LF-0,5%,1/16W,CHIP,CA
PWR_LED_CPLD             U25              B5       10M02SCU169C8G-10M02SCU169C8G,A
PWR_LED_P3V3_AUX         C321             1        Q_CAP_0402-0.1UF,25V,10%,X7R,CA
PWR_LED_P3V3_AUX         D14              A        Q_LED_SMLF-LED_BLUE,12-215/BHCA
PWR_LED_P3V3_AUX         R568             2        Q_RES_0402LF-1K,1%,1/16W,CHIP,A
Q7_D                     Q7               3        MOSFET_N_123-BSS123-7-F,SMLF,IA
Q7_D                     R42              2        Q_RES_0402LF-10K,1%,1/16W,CHIPA
QSPI_2_PLD_CLK           GF1              B44      FCONN168_ME1016810106011-FCONNA
QSPI_2_PLD_CLK           R678             2        Q_RES_0402LF-33       ,1%  ,1/B
QSPI_2_PLD_CS0_N         GF1              B45      FCONN168_ME1016810106011-FCONNA
QSPI_2_PLD_CS0_N         R677             1        Q_RES_0402LF-33       ,1%  ,1/B
QSPI_2_PLD_CS1_N         GF1              B42      FCONN168_ME1016810106011-FCONNA
QSPI_2_PLD_CS1_N         R107             1        Q_RES_0402LF-33       ,1%  ,1/B
QSPI_2_PLD_IO0           GF1              B46      FCONN168_ME1016810106011-FCONNA
QSPI_2_PLD_IO0           R679             2        Q_RES_0402LF-33       ,1%  ,1/B
QSPI_2_PLD_IO1           GF1              B47      FCONN168_ME1016810106011-FCONNA
QSPI_2_PLD_IO1           R680             2        Q_RES_0402LF-33       ,1%  ,1/B
QSPI_2_PLD_IO2           GF1              B48      FCONN168_ME1016810106011-FCONNA
QSPI_2_PLD_IO2           R681             2        Q_RES_0402LF-33       ,1%  ,1/B
QSPI_2_PLD_IO3           GF1              B49      FCONN168_ME1016810106011-FCONNA
QSPI_2_PLD_IO3           R682             2        Q_RES_0402LF-33       ,1%  ,1/B
REAR_ID_RST_BTN_N        C199             1        Q_CAP_C0402-1UF,25V,10%,X6S,CHA
REAR_ID_RST_BTN_N        R504             2        Q_RES_0402LF-8.2K     ,5%  ,1/A
REAR_ID_RST_BTN_N        SW7              2        SW2S_TA31E2KQTR-SW2S_TA3-1E2K-A
REAR_ID_RST_BTN_N        U32              2        74LVC1G17GW-74LVC1G17GW,SMLF,IA
REAR_PWR_BTN_N           C198             1        Q_CAP_C0402-1UF,25V,10%,X6S,CHA
REAR_PWR_BTN_N           R768             2        Q_RES_0402LF-8.2K     ,5%  ,1/A
REAR_PWR_BTN_N           SW6              2        SW2S_TA31E2KQTR-SW2S_TA3-1E2K-A
REAR_PWR_BTN_N           U31              2        74LVC1G07GW-74LVC1G07GW,SMLF,IA
RGMII_BMC_MDC            R803             1        Q_RES_0402LF-33       ,1%  ,1/A
RGMII_BMC_MDC            U5               M24      AST2600A1GP-AST2600A1-GP,SMLF,A
RGMII_BMC_MDC_R          R283             2        Q_RES_0402LF-1.5K,1%,1/16W,EMPA
RGMII_BMC_MDC_R          R803             2        Q_RES_0402LF-33       ,1%  ,1/A
RGMII_BMC_MDC_R          U7               48       BCM54612EB1KMLG-BCM54612EB1KMLA
RGMII_BMC_MDIO           R804             1        Q_RES_0402LF-33       ,1%  ,1/A
RGMII_BMC_MDIO           U5               M25      AST2600A1GP-AST2600A1-GP,SMLF,A
RGMII_BMC_MDIO_R         R285             2        Q_RES_0402LF-1.5K,1%,1/16W,CHIA
RGMII_BMC_MDIO_R         R804             2        Q_RES_0402LF-33       ,1%  ,1/A
RGMII_BMC_MDIO_R         U7               47       BCM54612EB1KMLG-BCM54612EB1KMLA
RGMII_BMC_RXD_<0>        R53              1        Q_RES_0402LF-33       ,1%  ,1/A
RGMII_BMC_RXD_<0>        U5               F23      AST2600A1GP-AST2600A1-GP,SMLF,A
RGMII_BMC_RXD_<1>        R54              1        Q_RES_0402LF-33       ,1%  ,1/A
RGMII_BMC_RXD_<1>        U5               F26      AST2600A1GP-AST2600A1-GP,SMLF,A
RGMII_BMC_RXD_<2>        R470             1        Q_RES_0402LF-33       ,1%  ,1/A
RGMII_BMC_RXD_<2>        U5               F25      AST2600A1GP-AST2600A1-GP,SMLF,A
RGMII_BMC_RXD_<3>        R471             1        Q_RES_0402LF-33       ,1%  ,1/A
RGMII_BMC_RXD_<3>        U5               E26      AST2600A1GP-AST2600A1-GP,SMLF,A
RGMII_BMC_RX_CLK         C152             1        Q_CAP_0402-22PF,50V,5%,EMPTY,TA
RGMII_BMC_RX_CLK         R297             1        Q_RES_0402LF-0,5%,1/16W,CHIP,CA
RGMII_BMC_RX_CLK         U7               33       BCM54612EB1KMLG-BCM54612EB1KMLA
RGMII_BMC_RX_CLK_R       R297             2        Q_RES_0402LF-0,5%,1/16W,CHIP,CA
RGMII_BMC_RX_CLK_R       U5               G23      AST2600A1GP-AST2600A1-GP,SMLF,A
RGMII_BMC_RX_CTRL        R52              1        Q_RES_0402LF-33       ,1%  ,1/A
RGMII_BMC_RX_CTRL        U5               G24      AST2600A1GP-AST2600A1-GP,SMLF,A
RGMII_BMC_RX_R_CTRL      R52              2        Q_RES_0402LF-33       ,1%  ,1/A
RGMII_BMC_RX_R_CTRL      U7               26       BCM54612EB1KMLG-BCM54612EB1KMLA
RGMII_BMC_R_RXD_<0>      R53              2        Q_RES_0402LF-33       ,1%  ,1/A
RGMII_BMC_R_RXD_<0>      U7               32       BCM54612EB1KMLG-BCM54612EB1KMLA
RGMII_BMC_R_RXD_<1>      R54              2        Q_RES_0402LF-33       ,1%  ,1/A
RGMII_BMC_R_RXD_<1>      U7               31       BCM54612EB1KMLG-BCM54612EB1KMLA
RGMII_BMC_R_RXD_<2>      R470             2        Q_RES_0402LF-33       ,1%  ,1/A
RGMII_BMC_R_RXD_<2>      U7               28       BCM54612EB1KMLG-BCM54612EB1KMLA
RGMII_BMC_R_RXD_<3>      R471             2        Q_RES_0402LF-33       ,1%  ,1/A
RGMII_BMC_R_RXD_<3>      U7               27       BCM54612EB1KMLG-BCM54612EB1KMLA
RGMII_BMC_TXD_<0>        R628             2        Q_RES_0402LF-22,5%,1/16W,CHIP,A
RGMII_BMC_TXD_<0>        U7               39       BCM54612EB1KMLG-BCM54612EB1KMLA
RGMII_BMC_TXD_<1>        R629             2        Q_RES_0402LF-22,5%,1/16W,CHIP,A
RGMII_BMC_TXD_<1>        U7               38       BCM54612EB1KMLG-BCM54612EB1KMLA
RGMII_BMC_TXD_<2>        R630             2        Q_RES_0402LF-22,5%,1/16W,CHIP,A
RGMII_BMC_TXD_<2>        U7               37       BCM54612EB1KMLG-BCM54612EB1KMLA
RGMII_BMC_TXD_<3>        R631             2        Q_RES_0402LF-22,5%,1/16W,CHIP,A
RGMII_BMC_TXD_<3>        U7               36       BCM54612EB1KMLG-BCM54612EB1KMLA
RGMII_BMC_TXD_R_<0>      R628             1        Q_RES_0402LF-22,5%,1/16W,CHIP,A
RGMII_BMC_TXD_R_<0>      U5               H22      AST2600A1GP-AST2600A1-GP,SMLF,A
RGMII_BMC_TXD_R_<1>      R629             1        Q_RES_0402LF-22,5%,1/16W,CHIP,A
RGMII_BMC_TXD_R_<1>      U5               H23      AST2600A1GP-AST2600A1-GP,SMLF,A
RGMII_BMC_TXD_R_<2>      R630             1        Q_RES_0402LF-22,5%,1/16W,CHIP,A
RGMII_BMC_TXD_R_<2>      U5               G22      AST2600A1GP-AST2600A1-GP,SMLF,A
RGMII_BMC_TXD_R_<3>      R631             1        Q_RES_0402LF-22,5%,1/16W,CHIP,A
RGMII_BMC_TXD_R_<3>      U5               F22      AST2600A1GP-AST2600A1-GP,SMLF,A
RGMII_BMC_TX_CLK         R538             2        Q_RES_0402LF-22,5%,1/16W,CHIP,A
RGMII_BMC_TX_CLK         U7               40       BCM54612EB1KMLG-BCM54612EB1KMLA
RGMII_BMC_TX_CTRL        R539             2        Q_RES_0402LF-22,5%,1/16W,CHIP,A
RGMII_BMC_TX_CTRL        U7               35       BCM54612EB1KMLG-BCM54612EB1KMLA
RGMII_BMC_TX_R_CLK       R538             1        Q_RES_0402LF-22,5%,1/16W,CHIP,A
RGMII_BMC_TX_R_CLK       U5               H24      AST2600A1GP-AST2600A1-GP,SMLF,A
RGMII_BMC_TX_R_CTRL      R539             1        Q_RES_0402LF-22,5%,1/16W,CHIP,A
RGMII_BMC_TX_R_CTRL      U5               J22      AST2600A1GP-AST2600A1-GP,SMLF,A
RMII_CSRDV               GF1              B19      FCONN168_ME1016810106011-FCONNA
RMII_CSRDV               R161             2        Q_RES_0402LF-4.7K,5%,1/16W,CHIA
RMII_CSRDV               U5               B25      AST2600A1GP-AST2600A1-GP,SMLF,A
RMII_OCP_RCLKI           GF1              B18      FCONN168_ME1016810106011-FCONNA
RMII_OCP_RCLKI           U5               C25      AST2600A1GP-AST2600A1-GP,SMLF,A
RMII_RXD0                GF1              B24      FCONN168_ME1016810106011-FCONNA
RMII_RXD0                U5               C24      AST2600A1GP-AST2600A1-GP,SMLF,A
RMII_RXD1                GF1              B25      FCONN168_ME1016810106011-FCONNA
RMII_RXD1                U5               B26      AST2600A1GP-AST2600A1-GP,SMLF,A
RMII_RXER                GF1              B23      FCONN168_ME1016810106011-FCONNA
RMII_RXER                R101             2        Q_RES_0402LF-4.7K,5%,1/16W,CHIA
RMII_RXER                U5               B24      AST2600A1GP-AST2600A1-GP,SMLF,A
RMII_TXD0                GF1              B21      FCONN168_ME1016810106011-FCONNA
RMII_TXD0                R172             2        Q_RES_0402LF-33       ,1%  ,1/A
RMII_TXD0_R              R172             1        Q_RES_0402LF-33       ,1%  ,1/A
RMII_TXD0_R              U5               E24      AST2600A1GP-AST2600A1-GP,SMLF,A
RMII_TXD1                GF1              B22      FCONN168_ME1016810106011-FCONNA
RMII_TXD1                R173             2        Q_RES_0402LF-33       ,1%  ,1/A
RMII_TXD1_R              R173             1        Q_RES_0402LF-33       ,1%  ,1/A
RMII_TXD1_R              U5               E25      AST2600A1GP-AST2600A1-GP,SMLF,A
RMII_TXEN                GF1              B20      FCONN168_ME1016810106011-FCONNA
RMII_TXEN                R103             2        Q_RES_0402LF-4.7K,5%,1/16W,CHIA
RMII_TXEN                R171             2        Q_RES_0402LF-33       ,1%  ,1/A
RMII_TXEN_R              R171             1        Q_RES_0402LF-33       ,1%  ,1/A
RMII_TXEN_R              U5               E23      AST2600A1GP-AST2600A1-GP,SMLF,A
RST_BMC_EXTRST_R1_N      R290             2        Q_RES_0402LF-47K,1%,1/16W,CHIPA
RST_BMC_EXTRST_R1_N      R291             2        Q_RES_0402LF-4.7K,1%,1/16W,CHIA
RST_BMC_EXTRST_R1_N      U12              D        MOSFET_N_SMLF-BSS138K,BSS138K,A
RST_BMC_EXTRST_R1_N      U13              4        SN74LVC1G07DCKR-SN74LVC1G07DCKA
RST_BMC_EXTRST_R2_N      Q1               C        MMBT39047F-MMBT3904-7-F,SMLF,IA
RST_BMC_EXTRST_R2_N      R106             2        Q_RES_0402LF-0,5%,1/16W,CHIP,CA
RST_BMC_EXTRST_R2_N      R110             2        Q_RES_0402LF-0,5%,1/16W,CHIP,CA
RST_BMC_EXTRST_R2_N      R287             2        Q_RES_0402LF-499,1%,1/16W,CHIPA
RST_BMC_EXTRST_R2_N      R636             2        Q_RES_0402LF-0,5%,1/16W,CHIP,CA
RST_BMC_EXTRST_R3_N      J10              2        SCONN11_9192031111LF-SCONN11_9A
RST_BMC_EXTRST_R3_N      R110             1        Q_RES_0402LF-0,5%,1/16W,CHIP,CA
RST_BMC_HW               R282             1        Q_RES_0402LF-0,5%,1/16W,CHIP,CA
RST_BMC_HW               R638             2        Q_RES_0402LF-33       ,1%  ,1/A
RST_BMC_HW_R             R638             1        Q_RES_0402LF-33       ,1%  ,1/A
RST_BMC_HW_R             U25              D12      10M02SCU169C8G-10M02SCU169C8G,A
RST_BMC_LPC_ESPI_N       GF1              B4       FCONN168_ME1016810106011-FCONNA
RST_BMC_LPC_ESPI_N       R117             2        Q_RES_0402LF-4.7K,5%,1/16W,CHIA
RST_BMC_LPC_ESPI_N       R120             1        Q_RES_0402LF-33       ,1%  ,1/A
RST_BMC_RSTBTN_OUT_N     R566             2        Q_RES_0402LF-0,5%,1/16W,CHIP,CA
RST_BMC_RSTBTN_OUT_N     R717             2        Q_RES_0402LF-4.7K,5%,1/16W,CHIA
RST_BMC_RSTBTN_OUT_N     U25              H3       10M02SCU169C8G-10M02SCU169C8G,A
RST_BMC_RSTBTN_OUT_R_N   R566             1        Q_RES_0402LF-0,5%,1/16W,CHIP,CA
RST_BMC_RSTBTN_OUT_R_N   U5               AA24     AST2600A1GP-AST2600A1-GP,SMLF,A
RST_BMC_SELF_HW          R271             1        Q_RES_0402LF-0,5%,1/16W,CHIP,CA
RST_BMC_SELF_HW          R450             1        Q_RES_0402LF-0,5%,1/16W,EMPTY,A
RST_BMC_SELF_HW          R494             2        Q_RES_0402LF-33       ,1%  ,1/A
RST_BMC_SELF_HW_D        C161             1        Q_CAP_C0402-1UF,25V,10%,X6S,CHA
RST_BMC_SELF_HW_D        D17              2        Q_DIODE_SMLF-SDMK0340L-7-F,IC,A
RST_BMC_SELF_HW_D        R313             1        Q_RES_0402LF-470K,1%,1/16W,CHIA
RST_BMC_SELF_HW_D_C      C161             2        Q_CAP_C0402-1UF,25V,10%,X6S,CHA
RST_BMC_SELF_HW_D_C      C173             1        Q_CAP_C0402-0.1UF,25V,10%,X6S,A
RST_BMC_SELF_HW_D_C      R314             1        Q_RES_0402LF-100K,1%,1/16W,CHIB
RST_BMC_SELF_HW_D_C      U12              G        MOSFET_N_SMLF-BSS138K,BSS138K,A
RST_BMC_SELF_HW_R1       R494             1        Q_RES_0402LF-33       ,1%  ,1/A
RST_BMC_SELF_HW_R1       U5               AF11     AST2600A1GP-AST2600A1-GP,SMLF,A
RST_BMC_SELF_HW_R2       R271             2        Q_RES_0402LF-0,5%,1/16W,CHIP,CA
RST_BMC_SELF_HW_R2       R641             2        Q_RES_0402LF-4.7K,5%,1/16W,CHIA
RST_BMC_SELF_HW_R2       U25              L12      10M02SCU169C8G-10M02SCU169C8G,A
RST_BMC_SELF_HW_R3       D17              1        Q_DIODE_SMLF-SDMK0340L-7-F,IC,A
RST_BMC_SELF_HW_R3       R282             2        Q_RES_0402LF-0,5%,1/16W,CHIP,CA
RST_BMC_SELF_HW_R3       R450             2        Q_RES_0402LF-0,5%,1/16W,EMPTY,A
RST_BMC_SELF_HW_R3       R633             2        Q_RES_0402LF-1K,1%,1/16W,EMPTYA
RST_BMC_SRST_BUF_R1_N    R315             2        Q_RES_0402LF-0,5%,1/16W,CHIP,CA
RST_BMC_SRST_BUF_R1_N    U13              2        SN74LVC1G07DCKR-SN74LVC1G07DCKA
RST_BMC_SRST_BUF_R_N     C223             1        Q_CAP_C0402-4700P,25V,10%,EMPTA
RST_BMC_SRST_BUF_R_N     R108             2        Q_RES_0402LF-49.9     ,1%  ,1/A
RST_BMC_SRST_BUF_R_N     R124             2        Q_RES_0402LF-2K,1%,1/16W,CHIP,A
RST_BMC_SRST_BUF_R_N     R125             1        Q_RES_0402LF-100,1%,1/16W,EMPTA
RST_BMC_SRST_BUF_R_N     R134             1        Q_RES_0402LF-100,1%,1/16W,CHIPA
RST_BMC_SRST_BUF_R_N     R192             2        Q_RES_0402LF-49.9     ,1%  ,1/A
RST_BMC_SRST_BUF_R_N     R315             1        Q_RES_0402LF-0,5%,1/16W,CHIP,CA
RST_BMC_SRST_N           R106             1        Q_RES_0402LF-0,5%,1/16W,CHIP,CA
RST_BMC_SRST_N           R125             2        Q_RES_0402LF-100,1%,1/16W,EMPTA
RST_BMC_SRST_N           U5               E10      AST2600A1GP-AST2600A1-GP,SMLF,A
RST_ESPI_LPC_BMC_N       R120             2        Q_RES_0402LF-33       ,1%  ,1/A
RST_ESPI_LPC_BMC_N       U5               AD8      AST2600A1GP-AST2600A1-GP,SMLF,A
RST_EXTRST_N             R447             1        Q_RES_0402LF-0,5%,1/16W,CHIP,CA
RST_EXTRST_N             R623             2        Q_RES_0402LF-4.7K,1%,1/16W,CHIA
RST_EXTRST_N             R636             1        Q_RES_0402LF-0,5%,1/16W,CHIP,CA
RST_EXTRST_N             U5               B10      AST2600A1GP-AST2600A1-GP,SMLF,A
RST_EXTRST_R_N           R447             2        Q_RES_0402LF-0,5%,1/16W,CHIP,CA
RST_EXTRST_R_N           U25              N5       10M02SCU169C8G-10M02SCU169C8G,A
RST_MB_STBY_N            GF1              A46      FCONN168_ME1016810106011-FCONNA
RST_MB_STBY_N            R263             1        Q_RES_0402LF-33       ,1%  ,1/A
RST_MB_STBY_R_N          R263             2        Q_RES_0402LF-33       ,1%  ,1/A
RST_MB_STBY_R_N          U25              H10      10M02SCU169C8G-10M02SCU169C8G,A
RST_PCA9548_SENSOR_N     R169             2        Q_RES_0402LF-4.7K,5%,1/16W,CHIA
RST_PCA9548_SENSOR_N     R704             1        Q_RES_0402LF-33       ,1%  ,1/A
RST_PCA9548_SENSOR_N     U25              H1       10M02SCU169C8G-10M02SCU169C8G,A
RST_PCA9548_SENSOR_R_N   R704             2        Q_RES_0402LF-33       ,1%  ,1/A
RST_PCA9548_SENSOR_R_N   U5               A25      AST2600A1GP-AST2600A1-GP,SMLF,A
RST_PLTRST_N             GF1              A51      FCONN168_ME1016810106011-FCONNA
RST_PLTRST_N             R34              2        Q_RES_0402LF-4.7K,5%,1/16W,CHIA
RST_PLTRST_N             R118             2        Q_RES_0402LF-100K,1%,1/16W,EMPA
RST_PLTRST_N             R168             1        Q_RES_0402LF-33       ,1%  ,1/A
RST_PLTRST_N             R503             2        Q_RES_0402LF-0,5%,1/16W,CHIP,CA
RST_PLTRST_N             R718             1        Q_RES_0402LF-33       ,1%  ,1/A
RST_PLTRST_N             U5               A7       AST2600A1GP-AST2600A1-GP,SMLF,A
RST_PLTRST_R1_N          R718             2        Q_RES_0402LF-33       ,1%  ,1/A
RST_PLTRST_R1_N          U25              B1       10M02SCU169C8G-10M02SCU169C8G,A
RST_PLTRST_R_N           R168             2        Q_RES_0402LF-33       ,1%  ,1/A
RST_PLTRST_R_N           U5               D22      AST2600A1GP-AST2600A1-GP,SMLF,A
RST_PLTRST_TPM_N         J5               2        SCONN11_9192031111LF-SCONN11_9A
RST_PLTRST_TPM_N         R503             1        Q_RES_0402LF-0,5%,1/16W,CHIP,CA
RST_ROT_CPU_N            GF1              A53      FCONN168_ME1016810106011-FCONNA
RST_ROT_CPU_N            R825             1        Q_RES_0402LF-33       ,1%  ,1/A
RST_ROT_CPU_N            R828             2        Q_RES_0402LF-4.7K,5%,1/16W,CHIA
RST_ROT_CPU_R_N          R825             2        Q_RES_0402LF-33       ,1%  ,1/A
RST_ROT_CPU_R_N          U25              L13      10M02SCU169C8G-10M02SCU169C8G,A
RST_RSMRST_N             R160             1        Q_RES_0402LF-33       ,1%  ,1/A
RST_RSMRST_N             R625             2        Q_RES_0402LF-4.7K,1%,1/16W,CHIA
RST_RSMRST_N             U25              F1       10M02SCU169C8G-10M02SCU169C8G,A
RST_RSMRST_R_N           R160             2        Q_RES_0402LF-33       ,1%  ,1/A
RST_RSMRST_R_N           U5               AF14     AST2600A1GP-AST2600A1-GP,SMLF,A
RST_RSTB_N               C142             2        Q_CAP_C0402-0.01UF,50V,10%,EMPA
RST_RSTB_N               R134             2        Q_RES_0402LF-100,1%,1/16W,CHIPA
RST_RSTB_N               R284             2        Q_RES_0402LF-4.7K,1%,1/16W,EMPA
RST_RSTB_N               U7               46       BCM54612EB1KMLG-BCM54612EB1KMLA
RST_SGPIO_RESET_BMC_N    R688             2        Q_RES_0402LF-33       ,1%  ,1/B
RST_SGPIO_RESET_BMC_N    U5               C23      AST2600A1GP-AST2600A1-GP,SMLF,A
RST_SGPIO_RESET_N        GF1              B39      FCONN168_ME1016810106011-FCONNA
RST_SGPIO_RESET_N        R69              2        Q_RES_0402LF-4.7K,5%,1/16W,CHIA
RST_SGPIO_RESET_N        R688             1        Q_RES_0402LF-33       ,1%  ,1/B
RST_SGPIO_RESET_N        R691             2        Q_RES_0402LF-33       ,1%  ,1/A
RST_SGPIO_RESET_R_N      R691             1        Q_RES_0402LF-33       ,1%  ,1/A
RST_SGPIO_RESET_R_N      U25              N9       10M02SCU169C8G-10M02SCU169C8G,A
RST_SPI_BMC_FLASH_R1_N   J121             3        SCONN16_ACASPI006P06-SCONN16_AA
RST_SPI_BMC_FLASH_R1_N   R562             1        Q_RES_0402LF-33       ,1%  ,1/B
RST_SPI_BMC_FLASH_R2_N   R561             1        Q_RES_0402LF-33       ,1%  ,1/B
RST_SPI_BMC_FLASH_R2_N   U28              3        MX66L1G45GMI08G-MX66L1G45GMI-0A
RST_SPI_FLASH_N          R561             2        Q_RES_0402LF-33       ,1%  ,1/B
RST_SPI_FLASH_N          R562             2        Q_RES_0402LF-33       ,1%  ,1/B
RST_SPI_FLASH_N          R563             2        Q_RES_0402LF-4.7K,1%,1/16W,CHIA
RST_SPI_FLASH_N          U5               B7       AST2600A1GP-AST2600A1-GP,SMLF,A
RST_SPI_PCH_FLASH_R1_N   J40              3        SCONN16_ACASPI006P06-SCONN16_AA
RST_SPI_PCH_FLASH_R1_N   R496             2        Q_RES_0402LF-4.7K,1%,1/16W,EMPA
RST_SRST_PLD_BMC_BUF_N   R108             1        Q_RES_0402LF-49.9     ,1%  ,1/A
RST_SRST_PLD_BMC_BUF_N   U6               4        SN74LVC2G07DCKR_SMLF-SN74LVC2GA
RST_SRST_PLD_BMC_R_N     R614             1        Q_RES_0402LF-100K,1%,1/16W,CHIA
RST_SRST_PLD_BMC_R_N     U6               3        SN74LVC2G07DCKR_SMLF-SN74LVC2GA
RST_SRST_PLD_BMC_R_N     U25              K2       10M02SCU169C8G-10M02SCU169C8G,A
RST_WDTRST_PLD_N         R452             2        Q_RES_0402LF-4.7K,5%,1/16W,CHIA
RST_WDTRST_PLD_N         R635             1        Q_RES_0402LF-33       ,1%  ,1/A
RST_WDTRST_PLD_N         R637             2        Q_RES_0402LF-0,5%,1/16W,CHIP,CA
RST_WDTRST_PLD_R1_N      R637             1        Q_RES_0402LF-0,5%,1/16W,CHIP,CA
RST_WDTRST_PLD_R1_N      U5               AD12     AST2600A1GP-AST2600A1-GP,SMLF,A
RST_WDTRST_PLD_R2_N      R635             2        Q_RES_0402LF-33       ,1%  ,1/A
RST_WDTRST_PLD_R2_N      U25              F8       10M02SCU169C8G-10M02SCU169C8G,A
SGPIO_BMC_M1_CLK         R148             2        Q_RES_0402LF-33       ,1%  ,1/A
SGPIO_BMC_M1_CLK         U5               A18      AST2600A1GP-AST2600A1-GP,SMLF,A
SGPIO_BMC_M1_DI          R433             2        Q_RES_0402LF-33       ,1%  ,1/A
SGPIO_BMC_M1_DI          U5               A17      AST2600A1GP-AST2600A1-GP,SMLF,A
SGPIO_BMC_M1_DO          R151             2        Q_RES_0402LF-33       ,1%  ,1/A
SGPIO_BMC_M1_DO          U5               C18      AST2600A1GP-AST2600A1-GP,SMLF,A
SGPIO_BMC_M1_LD          R150             2        Q_RES_0402LF-33       ,1%  ,1/A
SGPIO_BMC_M1_LD          U5               B18      AST2600A1GP-AST2600A1-GP,SMLF,A
SGPIO_CLK_0              GF1              B30      FCONN168_ME1016810106011-FCONNA
SGPIO_CLK_0              R64              1        Q_RES_0402LF-0,5%,1/16W,EMPTY,A
SGPIO_CLK_0              R82              2        Q_RES_0402LF-2K,1%,1/16W,CHIP,A
SGPIO_CLK_0              R434             2        Q_RES_0402LF-33       ,1%  ,1/A
SGPIO_CLK_1              GF1              B35      FCONN168_ME1016810106011-FCONNA
SGPIO_CLK_1              R63              1        Q_RES_0402LF-0,5%,1/16W,EMPTY,A
SGPIO_CLK_1              R76              2        Q_RES_0402LF-2K,1%,1/16W,CHIP,A
SGPIO_CLK_1              R148             1        Q_RES_0402LF-33       ,1%  ,1/A
SGPIO_CLK_PLD_0          R434             1        Q_RES_0402LF-33       ,1%  ,1/A
SGPIO_CLK_PLD_0          U25              K6       10M02SCU169C8G-10M02SCU169C8G,A
SGPIO_DI_0               GF1              B31      FCONN168_ME1016810106011-FCONNA
SGPIO_DI_0               R78              2        Q_RES_0402LF-2K,1%,1/16W,CHIP,A
SGPIO_DI_0               R437             2        Q_RES_0402LF-33       ,1%  ,1/A
SGPIO_DI_1               GF1              B36      FCONN168_ME1016810106011-FCONNA
SGPIO_DI_1               R74              2        Q_RES_0402LF-2K,1%,1/16W,CHIP,A
SGPIO_DI_1               R433             1        Q_RES_0402LF-33       ,1%  ,1/A
SGPIO_DO_0               GF1              B29      FCONN168_ME1016810106011-FCONNA
SGPIO_DO_0               R79              2        Q_RES_0402LF-2K,1%,1/16W,CHIP,A
SGPIO_DO_0               R435             2        Q_RES_0402LF-33       ,1%  ,1/A
SGPIO_DO_1               GF1              B34      FCONN168_ME1016810106011-FCONNA
SGPIO_DO_1               R75              2        Q_RES_0402LF-2K,1%,1/16W,CHIP,A
SGPIO_DO_1               R151             1        Q_RES_0402LF-33       ,1%  ,1/A
SGPIO_LD_0               GF1              B32      FCONN168_ME1016810106011-FCONNA
SGPIO_LD_0               R77              2        Q_RES_0402LF-1K,1%,1/16W,EMPTYA
SGPIO_LD_0               R436             2        Q_RES_0402LF-33       ,1%  ,1/A
SGPIO_LD_1               GF1              B37      FCONN168_ME1016810106011-FCONNA
SGPIO_LD_1               R73              2        Q_RES_0402LF-1K,1%,1/16W,EMPTYA
SGPIO_LD_1               R150             1        Q_RES_0402LF-33       ,1%  ,1/A
SGPIO_PLD_DI_0           R437             1        Q_RES_0402LF-33       ,1%  ,1/A
SGPIO_PLD_DI_0           U25              N11      10M02SCU169C8G-10M02SCU169C8G,A
SGPIO_PLD_DO_0           R435             1        Q_RES_0402LF-33       ,1%  ,1/A
SGPIO_PLD_DO_0           U25              M9       10M02SCU169C8G-10M02SCU169C8G,A
SGPIO_PLD_LD_0           R436             1        Q_RES_0402LF-33       ,1%  ,1/A
SGPIO_PLD_LD_0           U25              J7       10M02SCU169C8G-10M02SCU169C8G,A
SMB_BMC_ALERT10_N        R449             1        Q_RES_0402LF-33       ,1%  ,1/A
SMB_BMC_ALERT10_N        R457             1        Q_RES_0402LF-0,5%,1/16W,CHIP,CA
SMB_BMC_ALERT10_N        R843             2        Q_RES_0402LF-4.7K,5%,1/16W,CHIA
SMB_BMC_ALERT10_R1_N     R457             2        Q_RES_0402LF-0,5%,1/16W,CHIP,CA
SMB_BMC_ALERT10_R1_N     U25              K1       10M02SCU169C8G-10M02SCU169C8G,A
SMB_BMC_ALERT10_R_N      R449             2        Q_RES_0402LF-33       ,1%  ,1/A
SMB_BMC_ALERT10_R_N      U5               AA17     AST2600A1GP-AST2600A1-GP,SMLF,A
SMB_BMC_ALERT12_N        R844             2        Q_RES_0402LF-4.7K,5%,1/16W,CHIA
SMB_BMC_ALERT12_N        U5               AE16     AST2600A1GP-AST2600A1-GP,SMLF,A
SMB_BMC_ALERT12_N        U25              B7       10M02SCU169C8G-10M02SCU169C8G,A
SMB_BMC_ALERT15_N        R408             1        Q_RES_0402LF-33       ,1%  ,1/A
SMB_BMC_ALERT15_N        R851             2        Q_RES_0402LF-4.7K,5%,1/16W,CHIA
SMB_BMC_ALERT15_N        U5               D21      AST2600A1GP-AST2600A1-GP,SMLF,A
SMB_BMC_ALERT15_R_N      R407             2        Q_RES_0402LF-4.7K,5%,1/16W,CHIA
SMB_BMC_ALERT15_R_N      R408             2        Q_RES_0402LF-33       ,1%  ,1/A
SMB_BMC_ALERT15_R_N      U4               3        TMP75AIDGKR-TMP75AIDGKR,SMLF,IA
SMB_BMC_ALERT16_N        R848             2        Q_RES_0402LF-4.7K,5%,1/16W,CHIA
SMB_BMC_ALERT16_N        U5               AC17     AST2600A1GP-AST2600A1-GP,SMLF,A
SMB_BMC_ALERT3_N         R268             2        Q_RES_0402LF-4.7K,5%,1/16W,CHIA
SMB_BMC_ALERT3_N         R442             1        Q_RES_0402LF-33       ,1%  ,1/A
SMB_BMC_ALERT3_N         R453             1        Q_RES_0402LF-0,5%,1/16W,CHIP,CA
SMB_BMC_ALERT3_R1_N      R453             2        Q_RES_0402LF-0,5%,1/16W,CHIP,CA
SMB_BMC_ALERT3_R1_N      U25              N3       10M02SCU169C8G-10M02SCU169C8G,A
SMB_BMC_ALERT3_R_N       R442             2        Q_RES_0402LF-33       ,1%  ,1/A
SMB_BMC_ALERT3_R_N       U5               H26      AST2600A1GP-AST2600A1-GP,SMLF,A
SMB_BMC_ALERT4_N         R269             2        Q_RES_0402LF-4.7K,5%,1/16W,CHIA
SMB_BMC_ALERT4_N         R443             1        Q_RES_0402LF-33       ,1%  ,1/A
SMB_BMC_ALERT4_N         R454             1        Q_RES_0402LF-0,5%,1/16W,CHIP,CA
SMB_BMC_ALERT4_R1_N      R454             2        Q_RES_0402LF-0,5%,1/16W,CHIP,CA
SMB_BMC_ALERT4_R1_N      U25              L2       10M02SCU169C8G-10M02SCU169C8G,A
SMB_BMC_ALERT4_R_N       R443             2        Q_RES_0402LF-33       ,1%  ,1/A
SMB_BMC_ALERT4_R_N       U5               J25      AST2600A1GP-AST2600A1-GP,SMLF,A
SMB_BMC_ALERT9_N         R448             1        Q_RES_0402LF-33       ,1%  ,1/A
SMB_BMC_ALERT9_N         R456             1        Q_RES_0402LF-0,5%,1/16W,CHIP,CA
SMB_BMC_ALERT9_N         R842             2        Q_RES_0402LF-4.7K,5%,1/16W,CHIA
SMB_BMC_ALERT9_R1_N      R456             2        Q_RES_0402LF-0,5%,1/16W,CHIP,CA
SMB_BMC_ALERT9_R1_N      U25              M3       10M02SCU169C8G-10M02SCU169C8G,A
SMB_BMC_ALERT9_R_N       R448             2        Q_RES_0402LF-33       ,1%  ,1/A
SMB_BMC_ALERT9_R_N       U5               AB16     AST2600A1GP-AST2600A1-GP,SMLF,A
SMB_BMC_MM10_R_SCL       R583             1        Q_RES_0402LF-33       ,1%  ,1/A
SMB_BMC_MM10_R_SCL       U5               E15      AST2600A1GP-AST2600A1-GP,SMLF,A
SMB_BMC_MM10_R_SDA       R584             1        Q_RES_0402LF-33       ,1%  ,1/A
SMB_BMC_MM10_R_SDA       U5               A13      AST2600A1GP-AST2600A1-GP,SMLF,A
SMB_BMC_MM10_SCL         GF1              A31      FCONN168_ME1016810106011-FCONNA
SMB_BMC_MM10_SCL         R262             2        Q_RES_0402LF-4.7K,5%,1/16W,CHIA
SMB_BMC_MM10_SCL         R583             2        Q_RES_0402LF-33       ,1%  ,1/A
SMB_BMC_MM10_SDA         GF1              A32      FCONN168_ME1016810106011-FCONNA
SMB_BMC_MM10_SDA         R521             2        Q_RES_0402LF-4.7K,5%,1/16W,CHIA
SMB_BMC_MM10_SDA         R584             2        Q_RES_0402LF-33       ,1%  ,1/A
SMB_BMC_MM12_R_SCL       R137             1        Q_RES_0402LF-33       ,1%  ,1/A
SMB_BMC_MM12_R_SCL       U5               L26      AST2600A1GP-AST2600A1-GP,SMLF,A
SMB_BMC_MM12_R_SDA       R144             1        Q_RES_0402LF-33       ,1%  ,1/A
SMB_BMC_MM12_R_SDA       U5               K24      AST2600A1GP-AST2600A1-GP,SMLF,A
SMB_BMC_MM12_SCL         GF1              A38      FCONN168_ME1016810106011-FCONNA
SMB_BMC_MM12_SCL         R137             2        Q_RES_0402LF-33       ,1%  ,1/A
SMB_BMC_MM12_SCL         R145             2        Q_RES_0402LF-4.7K,5%,1/16W,CHIA
SMB_BMC_MM12_SDA         GF1              A39      FCONN168_ME1016810106011-FCONNA
SMB_BMC_MM12_SDA         R144             2        Q_RES_0402LF-33       ,1%  ,1/A
SMB_BMC_MM12_SDA         R149             2        Q_RES_0402LF-4.7K,5%,1/16W,CHIA
SMB_BMC_MM13_R_SCL       R423             1        Q_RES_0402LF-33       ,1%  ,1/A
SMB_BMC_MM13_R_SCL       R817             1        Q_RES_0402LF-100K,1%,1/16W,EMPB
SMB_BMC_MM13_R_SCL       U5               K26      AST2600A1GP-AST2600A1-GP,SMLF,A
SMB_BMC_MM13_R_SDA       R424             1        Q_RES_0402LF-33       ,1%  ,1/A
SMB_BMC_MM13_R_SDA       R818             1        Q_RES_0402LF-100K,1%,1/16W,EMPB
SMB_BMC_MM13_R_SDA       U5               L24      AST2600A1GP-AST2600A1-GP,SMLF,A
SMB_BMC_MM13_SCL         GF1              A40      FCONN168_ME1016810106011-FCONNA
SMB_BMC_MM13_SCL         R422             2        Q_RES_0402LF-4.7K,5%,1/16W,CHIA
SMB_BMC_MM13_SCL         R423             2        Q_RES_0402LF-33       ,1%  ,1/A
SMB_BMC_MM13_SDA         GF1              A41      FCONN168_ME1016810106011-FCONNA
SMB_BMC_MM13_SDA         R424             2        Q_RES_0402LF-33       ,1%  ,1/A
SMB_BMC_MM13_SDA         R428             2        Q_RES_0402LF-4.7K,5%,1/16W,CHIA
SMB_BMC_MM14_R1_SCL      GF1              A1       FCONN168_ME1016810106011-FCONNA
SMB_BMC_MM14_R1_SCL      R36              2        Q_RES_0402LF-33       ,1%  ,1/A
SMB_BMC_MM14_R1_SDA      GF1              A2       FCONN168_ME1016810106011-FCONNA
SMB_BMC_MM14_R1_SDA      R46              2        Q_RES_0402LF-33       ,1%  ,1/A
SMB_BMC_MM14_R_SCL       R425             1        Q_RES_0402LF-33       ,1%  ,1/A
SMB_BMC_MM14_R_SCL       R819             1        Q_RES_0402LF-100K,1%,1/16W,EMPB
SMB_BMC_MM14_R_SCL       U5               L23      AST2600A1GP-AST2600A1-GP,SMLF,A
SMB_BMC_MM14_R_SDA       R426             1        Q_RES_0402LF-33       ,1%  ,1/A
SMB_BMC_MM14_R_SDA       R820             1        Q_RES_0402LF-100K,1%,1/16W,EMPB
SMB_BMC_MM14_R_SDA       U5               K25      AST2600A1GP-AST2600A1-GP,SMLF,A
SMB_BMC_MM14_SCL         R36              1        Q_RES_0402LF-33       ,1%  ,1/A
SMB_BMC_MM14_SCL         R425             2        Q_RES_0402LF-33       ,1%  ,1/A
SMB_BMC_MM14_SCL         R429             2        Q_RES_0402LF-4.7K,5%,1/16W,CHIA
SMB_BMC_MM14_SDA         R46              1        Q_RES_0402LF-33       ,1%  ,1/A
SMB_BMC_MM14_SDA         R426             2        Q_RES_0402LF-33       ,1%  ,1/A
SMB_BMC_MM14_SDA         R438             2        Q_RES_0402LF-4.7K,5%,1/16W,CHIA
SMB_BMC_MM15_R1_SCL      R410             2        Q_RES_0402LF-33       ,1%  ,1/A
SMB_BMC_MM15_R1_SCL      U4               2        TMP75AIDGKR-TMP75AIDGKR,SMLF,IA
SMB_BMC_MM15_R1_SDA      R409             2        Q_RES_0402LF-33       ,1%  ,1/A
SMB_BMC_MM15_R1_SDA      U4               1        TMP75AIDGKR-TMP75AIDGKR,SMLF,IA
SMB_BMC_MM15_R2_SCL      R420             1        Q_RES_0402LF-33       ,1%  ,1/A
SMB_BMC_MM15_R2_SCL      U19              6        M24128BWDW6TP-M24128-BWDW6TP,SA
SMB_BMC_MM15_R2_SDA      R421             1        Q_RES_0402LF-33       ,1%  ,1/A
SMB_BMC_MM15_R2_SDA      U19              5        M24128BWDW6TP-M24128-BWDW6TP,SA
SMB_BMC_MM15_R3_SCL      R272             2        Q_RES_0402LF-0,5%,1/16W,CHIP,CA
SMB_BMC_MM15_R3_SCL      U25              E10      10M02SCU169C8G-10M02SCU169C8G,A
SMB_BMC_MM15_R3_SDA      R303             2        Q_RES_0402LF-0,5%,1/16W,CHIP,CA
SMB_BMC_MM15_R3_SDA      U25              D9       10M02SCU169C8G-10M02SCU169C8G,A
SMB_BMC_MM15_R_SCL       R162             2        Q_RES_0402LF-33       ,1%  ,1/A
SMB_BMC_MM15_R_SCL       U5               D18      AST2600A1GP-AST2600A1-GP,SMLF,A
SMB_BMC_MM15_R_SDA       R236             2        Q_RES_0402LF-33       ,1%  ,1/A
SMB_BMC_MM15_R_SDA       U5               B17      AST2600A1GP-AST2600A1-GP,SMLF,A
SMB_BMC_MM15_SCL         R47              2        Q_RES_0402LF-33       ,1%  ,1/B
SMB_BMC_MM15_SCL         R136             2        Q_RES_0402LF-33       ,1%  ,1/B
SMB_BMC_MM15_SCL         R162             1        Q_RES_0402LF-33       ,1%  ,1/A
SMB_BMC_MM15_SCL         R272             1        Q_RES_0402LF-0,5%,1/16W,CHIP,CA
SMB_BMC_MM15_SCL         R410             1        Q_RES_0402LF-33       ,1%  ,1/A
SMB_BMC_MM15_SCL         R420             2        Q_RES_0402LF-33       ,1%  ,1/A
SMB_BMC_MM15_SCL         R610             2        Q_RES_0402LF-4.7K,5%,1/16W,CHIA
SMB_BMC_MM15_SDA         R33              1        Q_RES_0402LF-33       ,1%  ,1/B
SMB_BMC_MM15_SDA         R126             1        Q_RES_0402LF-33       ,1%  ,1/B
SMB_BMC_MM15_SDA         R236             1        Q_RES_0402LF-33       ,1%  ,1/A
SMB_BMC_MM15_SDA         R303             1        Q_RES_0402LF-0,5%,1/16W,CHIP,CA
SMB_BMC_MM15_SDA         R409             1        Q_RES_0402LF-33       ,1%  ,1/A
SMB_BMC_MM15_SDA         R421             2        Q_RES_0402LF-33       ,1%  ,1/A
SMB_BMC_MM15_SDA         R692             2        Q_RES_0402LF-4.7K,5%,1/16W,CHIA
SMB_BMC_MM16_R1_SCL      D13              2        PCA9517ADP_SMLF-PCA9517ADP,IC,A
SMB_BMC_MM16_R1_SCL      R135             2        Q_RES_0402LF-0,5%,1/16W,CHIP,CA
SMB_BMC_MM16_R1_SDA      D13              3        PCA9517ADP_SMLF-PCA9517ADP,IC,A
SMB_BMC_MM16_R1_SDA      R294             2        Q_RES_0402LF-0,5%,1/16W,CHIP,CA
SMB_BMC_MM16_R_SCL       R152             2        Q_RES_0402LF-33       ,1%  ,1/A
SMB_BMC_MM16_R_SCL       U5               C17      AST2600A1GP-AST2600A1-GP,SMLF,A
SMB_BMC_MM16_R_SDA       R153             2        Q_RES_0402LF-33       ,1%  ,1/A
SMB_BMC_MM16_R_SDA       U5               E18      AST2600A1GP-AST2600A1-GP,SMLF,A
SMB_BMC_MM16_SCL         R135             1        Q_RES_0402LF-0,5%,1/16W,CHIP,CA
SMB_BMC_MM16_SCL         R152             1        Q_RES_0402LF-33       ,1%  ,1/A
SMB_BMC_MM16_SCL         R264             2        Q_RES_0402LF-4.7K,5%,1/16W,CHIA
SMB_BMC_MM16_SDA         R153             1        Q_RES_0402LF-33       ,1%  ,1/A
SMB_BMC_MM16_SDA         R265             2        Q_RES_0402LF-4.7K,5%,1/16W,CHIA
SMB_BMC_MM16_SDA         R294             1        Q_RES_0402LF-0,5%,1/16W,CHIP,CA
SMB_BMC_MM1_R_SCL        R132             1        Q_RES_0402LF-33       ,1%  ,1/A
SMB_BMC_MM1_R_SCL        U5               B20      AST2600A1GP-AST2600A1-GP,SMLF,A
SMB_BMC_MM1_R_SDA        R133             1        Q_RES_0402LF-33       ,1%  ,1/A
SMB_BMC_MM1_R_SDA        U5               A20      AST2600A1GP-AST2600A1-GP,SMLF,A
SMB_BMC_MM1_SCL          GF1              A3       FCONN168_ME1016810106011-FCONNA
SMB_BMC_MM1_SCL          R132             2        Q_RES_0402LF-33       ,1%  ,1/A
SMB_BMC_MM1_SCL          R244             2        Q_RES_0402LF-4.7K,5%,1/16W,CHIA
SMB_BMC_MM1_SDA          GF1              A4       FCONN168_ME1016810106011-FCONNA
SMB_BMC_MM1_SDA          R133             2        Q_RES_0402LF-33       ,1%  ,1/A
SMB_BMC_MM1_SDA          R245             2        Q_RES_0402LF-4.7K,5%,1/16W,CHIA
SMB_BMC_MM2_R_SCL        R165             1        Q_RES_0402LF-33       ,1%  ,1/A
SMB_BMC_MM2_R_SCL        U5               E19      AST2600A1GP-AST2600A1-GP,SMLF,A
SMB_BMC_MM2_R_SDA        R394             1        Q_RES_0402LF-33       ,1%  ,1/A
SMB_BMC_MM2_R_SDA        U5               D20      AST2600A1GP-AST2600A1-GP,SMLF,A
SMB_BMC_MM2_SCL          GF1              A5       FCONN168_ME1016810106011-FCONNA
SMB_BMC_MM2_SCL          R165             2        Q_RES_0402LF-33       ,1%  ,1/A
SMB_BMC_MM2_SCL          R246             2        Q_RES_0402LF-4.7K,5%,1/16W,CHIA
SMB_BMC_MM2_SDA          GF1              A6       FCONN168_ME1016810106011-FCONNA
SMB_BMC_MM2_SDA          R247             2        Q_RES_0402LF-4.7K,5%,1/16W,CHIA
SMB_BMC_MM2_SDA          R394             2        Q_RES_0402LF-33       ,1%  ,1/A
SMB_BMC_MM3_R_SCL        R589             1        Q_RES_0402LF-33       ,1%  ,1/A
SMB_BMC_MM3_R_SCL        U5               C19      AST2600A1GP-AST2600A1-GP,SMLF,A
SMB_BMC_MM3_R_SDA        R590             1        Q_RES_0402LF-33       ,1%  ,1/A
SMB_BMC_MM3_R_SDA        U5               A19      AST2600A1GP-AST2600A1-GP,SMLF,A
SMB_BMC_MM3_SCL          GF1              A7       FCONN168_ME1016810106011-FCONNA
SMB_BMC_MM3_SCL          R248             2        Q_RES_0402LF-4.7K,5%,1/16W,CHIA
SMB_BMC_MM3_SCL          R589             2        Q_RES_0402LF-33       ,1%  ,1/A
SMB_BMC_MM3_SDA          GF1              A8       FCONN168_ME1016810106011-FCONNA
SMB_BMC_MM3_SDA          R249             2        Q_RES_0402LF-4.7K,5%,1/16W,CHIA
SMB_BMC_MM3_SDA          R590             2        Q_RES_0402LF-33       ,1%  ,1/A
SMB_BMC_MM4_R_SCL        R138             1        Q_RES_0402LF-33       ,1%  ,1/A
SMB_BMC_MM4_R_SCL        U5               C20      AST2600A1GP-AST2600A1-GP,SMLF,A
SMB_BMC_MM4_R_SDA        R139             1        Q_RES_0402LF-33       ,1%  ,1/A
SMB_BMC_MM4_R_SDA        U5               D19      AST2600A1GP-AST2600A1-GP,SMLF,A
SMB_BMC_MM4_SCL          GF1              A9       FCONN168_ME1016810106011-FCONNA
SMB_BMC_MM4_SCL          R138             2        Q_RES_0402LF-33       ,1%  ,1/A
SMB_BMC_MM4_SCL          R250             2        Q_RES_0402LF-4.7K,5%,1/16W,CHIA
SMB_BMC_MM4_SDA          GF1              A10      FCONN168_ME1016810106011-FCONNA
SMB_BMC_MM4_SDA          R139             2        Q_RES_0402LF-33       ,1%  ,1/A
SMB_BMC_MM4_SDA          R251             2        Q_RES_0402LF-4.7K,5%,1/16W,CHIA
SMB_BMC_MM5_R_SCL        R71              1        Q_RES_0402LF-33       ,1%  ,1/A
SMB_BMC_MM5_R_SCL        R252             2        Q_RES_0402LF-4.7K,5%,1/16W,CHIA
SMB_BMC_MM5_R_SCL        U5               A11      AST2600A1GP-AST2600A1-GP,SMLF,A
SMB_BMC_MM5_R_SDA        R93              1        Q_RES_0402LF-33       ,1%  ,1/A
SMB_BMC_MM5_R_SDA        R253             2        Q_RES_0402LF-4.7K,5%,1/16W,CHIA
SMB_BMC_MM5_R_SDA        U5               C11      AST2600A1GP-AST2600A1-GP,SMLF,A
SMB_BMC_MM5_SCL          GF1              A21      FCONN168_ME1016810106011-FCONNA
SMB_BMC_MM5_SCL          R71              2        Q_RES_0402LF-33       ,1%  ,1/A
SMB_BMC_MM5_SDA          GF1              A22      FCONN168_ME1016810106011-FCONNA
SMB_BMC_MM5_SDA          R93              2        Q_RES_0402LF-33       ,1%  ,1/A
SMB_BMC_MM6_R_SCL        R142             1        Q_RES_0402LF-33       ,1%  ,1/A
SMB_BMC_MM6_R_SCL        U5               D12      AST2600A1GP-AST2600A1-GP,SMLF,A
SMB_BMC_MM6_R_SDA        R143             1        Q_RES_0402LF-33       ,1%  ,1/A
SMB_BMC_MM6_R_SDA        U5               E13      AST2600A1GP-AST2600A1-GP,SMLF,A
SMB_BMC_MM6_SCL          GF1              A23      FCONN168_ME1016810106011-FCONNA
SMB_BMC_MM6_SCL          R142             2        Q_RES_0402LF-33       ,1%  ,1/A
SMB_BMC_MM6_SCL          R254             2        Q_RES_0402LF-4.7K,5%,1/16W,CHIA
SMB_BMC_MM6_SDA          GF1              A24      FCONN168_ME1016810106011-FCONNA
SMB_BMC_MM6_SDA          R143             2        Q_RES_0402LF-33       ,1%  ,1/A
SMB_BMC_MM6_SDA          R255             2        Q_RES_0402LF-4.7K,5%,1/16W,CHIA
SMB_BMC_MM7_R_SCL        R256             2        Q_RES_0402LF-4.7K,5%,1/16W,CHIA
SMB_BMC_MM7_R_SCL        R567             1        Q_RES_0402LF-33       ,1%  ,1/A
SMB_BMC_MM7_R_SCL        U5               D11      AST2600A1GP-AST2600A1-GP,SMLF,A
SMB_BMC_MM7_R_SDA        R257             2        Q_RES_0402LF-4.7K,5%,1/16W,CHIA
SMB_BMC_MM7_R_SDA        R570             1        Q_RES_0402LF-33       ,1%  ,1/A
SMB_BMC_MM7_R_SDA        U5               E11      AST2600A1GP-AST2600A1-GP,SMLF,A
SMB_BMC_MM7_SCL          GF1              A25      FCONN168_ME1016810106011-FCONNA
SMB_BMC_MM7_SCL          R567             2        Q_RES_0402LF-33       ,1%  ,1/A
SMB_BMC_MM7_SDA          GF1              A26      FCONN168_ME1016810106011-FCONNA
SMB_BMC_MM7_SDA          R570             2        Q_RES_0402LF-33       ,1%  ,1/A
SMB_BMC_MM8_R_SCL        R146             1        Q_RES_0402LF-33       ,1%  ,1/A
SMB_BMC_MM8_R_SCL        U5               F13      AST2600A1GP-AST2600A1-GP,SMLF,A
SMB_BMC_MM8_R_SDA        R147             1        Q_RES_0402LF-33       ,1%  ,1/A
SMB_BMC_MM8_R_SDA        U5               E12      AST2600A1GP-AST2600A1-GP,SMLF,A
SMB_BMC_MM8_SCL          GF1              A27      FCONN168_ME1016810106011-FCONNA
SMB_BMC_MM8_SCL          R146             2        Q_RES_0402LF-33       ,1%  ,1/A
SMB_BMC_MM8_SCL          R258             2        Q_RES_0402LF-4.7K,5%,1/16W,CHIA
SMB_BMC_MM8_SDA          GF1              A28      FCONN168_ME1016810106011-FCONNA
SMB_BMC_MM8_SDA          R147             2        Q_RES_0402LF-33       ,1%  ,1/A
SMB_BMC_MM8_SDA          R259             2        Q_RES_0402LF-4.7K,5%,1/16W,CHIA
SMB_BMC_MM9_R_SCL        R580             1        Q_RES_0402LF-33       ,1%  ,1/A
SMB_BMC_MM9_R_SCL        U5               D15      AST2600A1GP-AST2600A1-GP,SMLF,A
SMB_BMC_MM9_R_SDA        R582             1        Q_RES_0402LF-33       ,1%  ,1/A
SMB_BMC_MM9_R_SDA        U5               A14      AST2600A1GP-AST2600A1-GP,SMLF,A
SMB_BMC_MM9_SCL          GF1              A29      FCONN168_ME1016810106011-FCONNA
SMB_BMC_MM9_SCL          R260             2        Q_RES_0402LF-4.7K,5%,1/16W,CHIA
SMB_BMC_MM9_SCL          R580             2        Q_RES_0402LF-33       ,1%  ,1/A
SMB_BMC_MM9_SDA          GF1              A30      FCONN168_ME1016810106011-FCONNA
SMB_BMC_MM9_SDA          R261             2        Q_RES_0402LF-4.7K,5%,1/16W,CHIA
SMB_BMC_MM9_SDA          R582             2        Q_RES_0402LF-33       ,1%  ,1/A
SMB_BMC_TPM_MM15_SCL     J10              10       SCONN11_9192031111LF-SCONN11_9A
SMB_BMC_TPM_MM15_SCL     R47              1        Q_RES_0402LF-33       ,1%  ,1/B
SMB_BMC_TPM_MM15_SDA     J10              6        SCONN11_9192031111LF-SCONN11_9A
SMB_BMC_TPM_MM15_SDA     R33              2        Q_RES_0402LF-33       ,1%  ,1/B
SMB_DEBUG_AUX_LVC3_USB_R1_SCL D13              7        PCA9517ADP_SMLF-PCA9517ADP,IC,A
SMB_DEBUG_AUX_LVC3_USB_R1_SCL R298             2        Q_RES_0402LF-4.7K,1%,1/16W,CHIA
SMB_DEBUG_AUX_LVC3_USB_R1_SCL R300             1        Q_RES_0402LF-0,5%,1/16W,CHIP,CA
SMB_DEBUG_AUX_LVC3_USB_R1_SDA D13              6        PCA9517ADP_SMLF-PCA9517ADP,IC,A
SMB_DEBUG_AUX_LVC3_USB_R1_SDA R299             2        Q_RES_0402LF-4.7K,1%,1/16W,CHIA
SMB_DEBUG_AUX_LVC3_USB_R1_SDA R302             1        Q_RES_0402LF-0,5%,1/16W,CHIP,CA
SMB_DEBUG_AUX_LVC3_USB_SCL J2               5        CONN9_GSB311131HR-CONN9_GSB311A
SMB_DEBUG_AUX_LVC3_USB_SCL R300             2        Q_RES_0402LF-0,5%,1/16W,CHIP,CA
SMB_DEBUG_AUX_LVC3_USB_SDA J2               6        CONN9_GSB311131HR-CONN9_GSB311A
SMB_DEBUG_AUX_LVC3_USB_SDA R302             2        Q_RES_0402LF-0,5%,1/16W,CHIP,CA
SMB_TPM_MM15_SCL         J5               10       SCONN11_9192031111LF-SCONN11_9A
SMB_TPM_MM15_SCL         R136             1        Q_RES_0402LF-33       ,1%  ,1/B
SMB_TPM_MM15_SDA         J5               6        SCONN11_9192031111LF-SCONN11_9A
SMB_TPM_MM15_SDA         R126             2        Q_RES_0402LF-33       ,1%  ,1/B
SPA_SIN_SW_BUF           R83              2        Q_RES_0402LF-0,5%,1/16W,CHIP,CA
SPA_SIN_SW_BUF           R95              2        Q_RES_0402LF-0,5%,1/16W,EMPTY,A
SPA_SIN_SW_BUF           U3               4        SN74LVC1G3157DCKR-SN74LVC1G315A
SPA_SIN_SW_DBG           R83              1        Q_RES_0402LF-0,5%,1/16W,CHIP,CA
SPA_SIN_SW_DBG           R193             2        Q_RES_0402LF-100K,1%,1/16W,CHIA
SPA_SIN_SW_DBG           U36              4        74HC1G126GW-74HC1G126GW,SMLF,IA
SPA_SIN_SW_MNUSB         R95              1        Q_RES_0402LF-0,5%,1/16W,EMPTY,A
SPA_SIN_SW_MNUSB         R397             1        Q_RES_0402LF-0,5%,1/16W,CHIP,CA
SPA_SIN_SW_MNUSB_R       R397             2        Q_RES_0402LF-0,5%,1/16W,CHIP,CA
SPA_SIN_SW_MNUSB_R       R398             2        Q_RES_0402LF-10K,1%,1/16W,CHIPA
SPA_SIN_SW_MNUSB_R       U17              7        FT234XDR-FT234XD-R,SMLF,IC,AL0A
SPA_SOUT_SW_BUF          R39              2        Q_RES_0402LF-0,5%,1/16W,CHIP,CA
SPA_SOUT_SW_BUF          R43              2        Q_RES_0402LF-0,5%,1/16W,EMPTY,A
SPA_SOUT_SW_BUF          U2               4        SN74LVC1G3157DCKR-SN74LVC1G315A
SPA_SOUT_SW_DBG          R39              1        Q_RES_0402LF-0,5%,1/16W,CHIP,CA
SPA_SOUT_SW_DBG          U29              2        74HC1G126GW-74HC1G126GW,SMLF,IA
SPA_SOUT_SW_MNUSB        R43              1        Q_RES_0402LF-0,5%,1/16W,EMPTY,A
SPA_SOUT_SW_MNUSB        U17              10       FT234XDR-FT234XD-R,SMLF,IC,AL0A
SPI_BMC_BIOS_CS0_N       R728             1        Q_RES_0402LF-0,5%,1/16W,CHIP,CA
SPI_BMC_BIOS_CS0_N       R799             1        Q_RES_0402LF-33       ,1%  ,1/A
SPI_BMC_BIOS_CS0_R1_N    R799             2        Q_RES_0402LF-33       ,1%  ,1/A
SPI_BMC_BIOS_CS0_R1_N    U5               AE8      AST2600A1GP-AST2600A1-GP,SMLF,A
SPI_BMC_BIOS_ROM_CLK     R174             1        Q_RES_0402LF-33       ,1%  ,1/A
SPI_BMC_BIOS_ROM_CLK     U5               AF8      AST2600A1GP-AST2600A1-GP,SMLF,A
SPI_BMC_BIOS_ROM_IO2     R724             1        Q_RES_0402LF-33       ,1%  ,1/A
SPI_BMC_BIOS_ROM_IO2     U5               AF9      AST2600A1GP-AST2600A1-GP,SMLF,A
SPI_BMC_BIOS_ROM_IO3     R725             1        Q_RES_0402LF-33       ,1%  ,1/A
SPI_BMC_BIOS_ROM_IO3     U5               AB10     AST2600A1GP-AST2600A1-GP,SMLF,A
SPI_BMC_BIOS_ROM_MISO    R176             1        Q_RES_0402LF-33       ,1%  ,1/A
SPI_BMC_BIOS_ROM_MISO    U5               AD9      AST2600A1GP-AST2600A1-GP,SMLF,A
SPI_BMC_BIOS_ROM_MOSI    R175             1        Q_RES_0402LF-33       ,1%  ,1/A
SPI_BMC_BIOS_ROM_MOSI    U5               AB9      AST2600A1GP-AST2600A1-GP,SMLF,A
SPI_BMC_BIOS_ROM_R_CLK   R174             2        Q_RES_0402LF-33       ,1%  ,1/A
SPI_BMC_BIOS_ROM_R_CLK   U30              10       IDTQS3VH257PAG_SMLF-IDTQS3VH25A
SPI_BMC_BIOS_ROM_R_IO2   R724             2        Q_RES_0402LF-33       ,1%  ,1/A
SPI_BMC_BIOS_ROM_R_IO2   U21              3        IDTQS3VH257PAG_SMLF-IDTQS3VH25A
SPI_BMC_BIOS_ROM_R_IO3   R725             2        Q_RES_0402LF-33       ,1%  ,1/A
SPI_BMC_BIOS_ROM_R_IO3   U30              6        IDTQS3VH257PAG_SMLF-IDTQS3VH25A
SPI_BMC_BIOS_ROM_R_MISO  R176             2        Q_RES_0402LF-33       ,1%  ,1/A
SPI_BMC_BIOS_ROM_R_MISO  U21              6        IDTQS3VH257PAG_SMLF-IDTQS3VH25A
SPI_BMC_BIOS_ROM_R_MOSI  R175             2        Q_RES_0402LF-33       ,1%  ,1/A
SPI_BMC_BIOS_ROM_R_MOSI  U30              3        IDTQS3VH257PAG_SMLF-IDTQS3VH25A
SPI_BMC_BIOS_SOURCE_CS0_N R728             2        Q_RES_0402LF-0,5%,1/16W,CHIP,CA
SPI_BMC_BIOS_SOURCE_CS0_N U21              10       IDTQS3VH257PAG_SMLF-IDTQS3VH25A
SPI_BMC_BOOT_CLK         R178             2        Q_RES_0402LF-33       ,1%  ,1/A
SPI_BMC_BOOT_CLK         R543             1        Q_RES_0402LF-33       ,1%  ,1/A
SPI_BMC_BOOT_CLK         R549             1        Q_RES_0402LF-33       ,1%  ,1/A
SPI_BMC_BOOT_CLK         R699             2        Q_RES_0402LF-4.7K,5%,1/16W,EMPA
SPI_BMC_BOOT_CS0_R1_N    R677             2        Q_RES_0402LF-33       ,1%  ,1/B
SPI_BMC_BOOT_CS0_R1_N    R801             2        Q_RES_0402LF-33       ,1%  ,1/A
SPI_BMC_BOOT_CS0_R1_N    U5               AB14     AST2600A1GP-AST2600A1-GP,SMLF,A
SPI_BMC_BOOT_CS0_R_N     R553             1        Q_RES_0402LF-33       ,1%  ,1/A
SPI_BMC_BOOT_CS0_R_N     R801             1        Q_RES_0402LF-33       ,1%  ,1/A
SPI_BMC_BOOT_CS1_R1_N    R107             2        Q_RES_0402LF-33       ,1%  ,1/B
SPI_BMC_BOOT_CS1_R1_N    R802             2        Q_RES_0402LF-33       ,1%  ,1/A
SPI_BMC_BOOT_CS1_R1_N    U5               AA13     AST2600A1GP-AST2600A1-GP,SMLF,A
SPI_BMC_BOOT_CS1_R_N     R547             1        Q_RES_0402LF-33       ,1%  ,1/A
SPI_BMC_BOOT_CS1_R_N     R802             1        Q_RES_0402LF-33       ,1%  ,1/A
SPI_BMC_BOOT_IO2         R181             2        Q_RES_0402LF-33       ,1%  ,1/A
SPI_BMC_BOOT_IO2         R545             1        Q_RES_0402LF-33       ,1%  ,1/A
SPI_BMC_BOOT_IO2         R551             1        Q_RES_0402LF-33       ,1%  ,1/A
SPI_BMC_BOOT_IO3         R182             2        Q_RES_0402LF-33       ,1%  ,1/A
SPI_BMC_BOOT_IO3         R548             1        Q_RES_0402LF-33       ,1%  ,1/A
SPI_BMC_BOOT_IO3         R554             1        Q_RES_0402LF-33       ,1%  ,1/A
SPI_BMC_BOOT_MISO        R180             2        Q_RES_0402LF-33       ,1%  ,1/A
SPI_BMC_BOOT_MISO        R546             1        Q_RES_0402LF-33       ,1%  ,1/A
SPI_BMC_BOOT_MISO        R552             1        Q_RES_0402LF-33       ,1%  ,1/A
SPI_BMC_BOOT_MISO        SW2              4        SW4S_DHNF02FTVTR-SW4S_DHNF-02FA
SPI_BMC_BOOT_MOSI        R140             2        Q_RES_0402LF-4.7K,5%,1/16W,CHIA
SPI_BMC_BOOT_MOSI        R179             2        Q_RES_0402LF-33       ,1%  ,1/A
SPI_BMC_BOOT_MOSI        R544             1        Q_RES_0402LF-33       ,1%  ,1/A
SPI_BMC_BOOT_MOSI        R550             1        Q_RES_0402LF-33       ,1%  ,1/A
SPI_BMC_BOOT_MOSI        SW2              3        SW4S_DHNF02FTVTR-SW4S_DHNF-02FA
SPI_BMC_CLK_FLASH_R1     J121             16       SCONN16_ACASPI006P06-SCONN16_AA
SPI_BMC_CLK_FLASH_R1     R549             2        Q_RES_0402LF-33       ,1%  ,1/A
SPI_BMC_CLK_FLASH_R2     R543             2        Q_RES_0402LF-33       ,1%  ,1/A
SPI_BMC_CLK_FLASH_R2     U28              16       MX66L1G45GMI08G-MX66L1G45GMI-0A
SPI_BMC_CLK_R            R109             2        Q_RES_0402LF-0,5%,1/16W,CHIP,CA
SPI_BMC_CLK_R            R178             1        Q_RES_0402LF-33       ,1%  ,1/A
SPI_BMC_CLK_R            R678             1        Q_RES_0402LF-33       ,1%  ,1/B
SPI_BMC_CLK_R            U5               AF13     AST2600A1GP-AST2600A1-GP,SMLF,A
SPI_BMC_CPLD_R_MOSI      Q7               2        MOSFET_N_123-BSS123-7-F,SMLF,IA
SPI_BMC_CPLD_R_MOSI      U5               AC11     AST2600A1GP-AST2600A1-GP,SMLF,A
SPI_BMC_CS0_FLASH_R1_N   J121             7        SCONN16_ACASPI006P06-SCONN16_AA
SPI_BMC_CS0_FLASH_R1_N   R553             2        Q_RES_0402LF-33       ,1%  ,1/A
SPI_BMC_CS0_FLASH_R1_N   R557             2        Q_RES_0402LF-4.7K,1%,1/16W,CHIA
SPI_BMC_CS1_FLASH_R2_N   R547             2        Q_RES_0402LF-33       ,1%  ,1/A
SPI_BMC_CS1_FLASH_R2_N   R558             2        Q_RES_0402LF-4.7K,1%,1/16W,EMPA
SPI_BMC_CS1_FLASH_R2_N   U28              7        MX66L1G45GMI08G-MX66L1G45GMI-0A
SPI_BMC_IO0_FLASH_R1     J121             15       SCONN16_ACASPI006P06-SCONN16_AA
SPI_BMC_IO0_FLASH_R1     R550             2        Q_RES_0402LF-33       ,1%  ,1/A
SPI_BMC_IO0_FLASH_R2     R544             2        Q_RES_0402LF-33       ,1%  ,1/A
SPI_BMC_IO0_FLASH_R2     U28              15       MX66L1G45GMI08G-MX66L1G45GMI-0A
SPI_BMC_IO1_FLASH_R1     J121             8        SCONN16_ACASPI006P06-SCONN16_AA
SPI_BMC_IO1_FLASH_R1     R552             2        Q_RES_0402LF-33       ,1%  ,1/A
SPI_BMC_IO1_FLASH_R2     R546             2        Q_RES_0402LF-33       ,1%  ,1/A
SPI_BMC_IO1_FLASH_R2     U28              8        MX66L1G45GMI08G-MX66L1G45GMI-0A
SPI_BMC_IO2_FLASH_R1     J121             9        SCONN16_ACASPI006P06-SCONN16_AA
SPI_BMC_IO2_FLASH_R1     R551             2        Q_RES_0402LF-33       ,1%  ,1/A
SPI_BMC_IO2_FLASH_R1     R555             2        Q_RES_0402LF-4.7K,1%,1/16W,CHIA
SPI_BMC_IO2_FLASH_R2     R545             2        Q_RES_0402LF-33       ,1%  ,1/A
SPI_BMC_IO2_FLASH_R2     R556             2        Q_RES_0402LF-4.7K,1%,1/16W,EMPA
SPI_BMC_IO2_FLASH_R2     U28              9        MX66L1G45GMI08G-MX66L1G45GMI-0A
SPI_BMC_IO2_R            R181             1        Q_RES_0402LF-33       ,1%  ,1/A
SPI_BMC_IO2_R            R681             1        Q_RES_0402LF-33       ,1%  ,1/B
SPI_BMC_IO2_R            U5               AE12     AST2600A1GP-AST2600A1-GP,SMLF,A
SPI_BMC_IO3_FLASH_R1     J121             1        SCONN16_ACASPI006P06-SCONN16_AA
SPI_BMC_IO3_FLASH_R1     R554             2        Q_RES_0402LF-33       ,1%  ,1/A
SPI_BMC_IO3_FLASH_R1     R559             2        Q_RES_0402LF-4.7K,1%,1/16W,CHIA
SPI_BMC_IO3_FLASH_R2     R548             2        Q_RES_0402LF-33       ,1%  ,1/A
SPI_BMC_IO3_FLASH_R2     R560             2        Q_RES_0402LF-4.7K,1%,1/16W,EMPA
SPI_BMC_IO3_FLASH_R2     U28              1        MX66L1G45GMI08G-MX66L1G45GMI-0A
SPI_BMC_IO3_R            R182             1        Q_RES_0402LF-33       ,1%  ,1/A
SPI_BMC_IO3_R            R682             1        Q_RES_0402LF-33       ,1%  ,1/B
SPI_BMC_IO3_R            U5               AF12     AST2600A1GP-AST2600A1-GP,SMLF,A
SPI_BMC_MISO_IO1_R       R98              2        Q_RES_0402LF-0,5%,1/16W,CHIP,CA
SPI_BMC_MISO_IO1_R       R180             1        Q_RES_0402LF-33       ,1%  ,1/A
SPI_BMC_MISO_IO1_R       R680             1        Q_RES_0402LF-33       ,1%  ,1/B
SPI_BMC_MISO_IO1_R       U5               AB13     AST2600A1GP-AST2600A1-GP,SMLF,A
SPI_BMC_MOSI_IO0_R       R97              2        Q_RES_0402LF-0,5%,1/16W,CHIP,CA
SPI_BMC_MOSI_IO0_R       R179             1        Q_RES_0402LF-33       ,1%  ,1/A
SPI_BMC_MOSI_IO0_R       R679             1        Q_RES_0402LF-33       ,1%  ,1/B
SPI_BMC_MOSI_IO0_R       U5               AC14     AST2600A1GP-AST2600A1-GP,SMLF,A
SPI_BMC_TPM_CLK_R        J10              1        SCONN11_9192031111LF-SCONN11_9A
SPI_BMC_TPM_CLK_R        R109             1        Q_RES_0402LF-0,5%,1/16W,CHIP,CA
SPI_BMC_TPM_CS2_N_R      J10              5        SCONN11_9192031111LF-SCONN11_9A
SPI_BMC_TPM_CS2_N_R      R100             1        Q_RES_0402LF-0,5%,1/16W,CHIP,CA
SPI_BMC_TPM_CS2_R1_N     R183             2        Q_RES_0402LF-33       ,1%  ,1/A
SPI_BMC_TPM_CS2_R1_N     U5               AC13     AST2600A1GP-AST2600A1-GP,SMLF,A
SPI_BMC_TPM_CS2_R_N      R100             2        Q_RES_0402LF-0,5%,1/16W,CHIP,CA
SPI_BMC_TPM_CS2_R_N      R183             1        Q_RES_0402LF-33       ,1%  ,1/A
SPI_BMC_TPM_CS2_R_N      R238             2        Q_RES_0402LF-4.7K,5%,1/16W,CHIA
SPI_BMC_TPM_MISO_R       J10              4        SCONN11_9192031111LF-SCONN11_9A
SPI_BMC_TPM_MISO_R       R98              1        Q_RES_0402LF-0,5%,1/16W,CHIP,CA
SPI_BMC_TPM_MOSI_R       J10              3        SCONN11_9192031111LF-SCONN11_9A
SPI_BMC_TPM_MOSI_R       R97              1        Q_RES_0402LF-0,5%,1/16W,CHIP,CA
SPI_PCH_CLK_FLASH_R1     J40              16       SCONN16_ACASPI006P06-SCONN16_AA
SPI_PCH_CLK_FLASH_R1     R481             2        Q_RES_0402LF-33       ,1%  ,1/A
SPI_PCH_CS0_FLASH_R1_N   J40              7        SCONN16_ACASPI006P06-SCONN16_AA
SPI_PCH_CS0_FLASH_R1_N   R485             2        Q_RES_0402LF-33       ,1%  ,1/A
SPI_PCH_CS0_FLASH_R1_N   R487             1        Q_RES_0402LF-4.7K,1%,1/16W,EMPA
SPI_PCH_CS0_FLASH_R1_N   R490             2        Q_RES_0402LF-4.7K,1%,1/16W,CHIA
SPI_PCH_IO0_FLASH_R1     J40              15       SCONN16_ACASPI006P06-SCONN16_AA
SPI_PCH_IO0_FLASH_R1     R482             2        Q_RES_0402LF-33       ,1%  ,1/A
SPI_PCH_IO1_FLASH_R1     J40              8        SCONN16_ACASPI006P06-SCONN16_AA
SPI_PCH_IO1_FLASH_R1     R484             2        Q_RES_0402LF-33       ,1%  ,1/A
SPI_PCH_IO2_FLASH_R1     J40              9        SCONN16_ACASPI006P06-SCONN16_AA
SPI_PCH_IO2_FLASH_R1     R483             2        Q_RES_0402LF-33       ,1%  ,1/A
SPI_PCH_IO2_FLASH_R1     R488             2        Q_RES_0402LF-4.7K,1%,1/16W,CHIA
SPI_PCH_IO3_FLASH_R1     J40              1        SCONN16_ACASPI006P06-SCONN16_AA
SPI_PCH_IO3_FLASH_R1     R486             2        Q_RES_0402LF-33       ,1%  ,1/A
SPI_PCH_IO3_FLASH_R1     R492             2        Q_RES_0402LF-4.7K,1%,1/16W,CHIA
SPI_PCH_MUXED_CLK        R481             1        Q_RES_0402LF-33       ,1%  ,1/A
SPI_PCH_MUXED_CLK        U30              9        IDTQS3VH257PAG_SMLF-IDTQS3VH25A
SPI_PCH_MUXED_CS0_N      R485             1        Q_RES_0402LF-33       ,1%  ,1/A
SPI_PCH_MUXED_CS0_N      U21              9        IDTQS3VH257PAG_SMLF-IDTQS3VH25A
SPI_PCH_MUXED_IO0        R482             1        Q_RES_0402LF-33       ,1%  ,1/A
SPI_PCH_MUXED_IO0        U30              4        IDTQS3VH257PAG_SMLF-IDTQS3VH25A
SPI_PCH_MUXED_IO1        R484             1        Q_RES_0402LF-33       ,1%  ,1/A
SPI_PCH_MUXED_IO1        U21              7        IDTQS3VH257PAG_SMLF-IDTQS3VH25A
SPI_PCH_MUXED_IO2        R483             1        Q_RES_0402LF-33       ,1%  ,1/A
SPI_PCH_MUXED_IO2        U21              4        IDTQS3VH257PAG_SMLF-IDTQS3VH25A
SPI_PCH_MUXED_IO3        R486             1        Q_RES_0402LF-33       ,1%  ,1/A
SPI_PCH_MUXED_IO3        U30              7        IDTQS3VH257PAG_SMLF-IDTQS3VH25A
SPI_PCH_SECURE_CS0_N     R864             2        Q_RES_0402LF-33       ,1%  ,1/A
SPI_PCH_SECURE_CS0_N     U21              11       IDTQS3VH257PAG_SMLF-IDTQS3VH25A
SPI_SYS_CS0_N            GF1              B12      FCONN168_ME1016810106011-FCONNA
SPI_SYS_CS0_N            R864             1        Q_RES_0402LF-33       ,1%  ,1/A
SPI_SYS_HOLD_R_IO3       GF1              B16      FCONN168_ME1016810106011-FCONNA
SPI_SYS_HOLD_R_IO3       R863             1        Q_RES_0402LF-33       ,1%  ,1/A
SPI_SYS_MUX_CLK          R859             2        Q_RES_0402LF-33       ,1%  ,1/A
SPI_SYS_MUX_CLK          U30              11       IDTQS3VH257PAG_SMLF-IDTQS3VH25A
SPI_SYS_MUX_HOLD_IO3     R863             2        Q_RES_0402LF-33       ,1%  ,1/A
SPI_SYS_MUX_HOLD_IO3     U30              5        IDTQS3VH257PAG_SMLF-IDTQS3VH25A
SPI_SYS_MUX_MISO         R861             2        Q_RES_0402LF-33       ,1%  ,1/A
SPI_SYS_MUX_MISO         U21              5        IDTQS3VH257PAG_SMLF-IDTQS3VH25A
SPI_SYS_MUX_MOSI         R860             2        Q_RES_0402LF-33       ,1%  ,1/A
SPI_SYS_MUX_MOSI         U30              2        IDTQS3VH257PAG_SMLF-IDTQS3VH25A
SPI_SYS_MUX_WP_IO2       R862             2        Q_RES_0402LF-33       ,1%  ,1/A
SPI_SYS_MUX_WP_IO2       U21              2        IDTQS3VH257PAG_SMLF-IDTQS3VH25A
SPI_SYS_R1_CLK           J5               1        SCONN11_9192031111LF-SCONN11_9A
SPI_SYS_R1_CLK           R501             1        Q_RES_0402LF-0,5%,1/16W,CHIP,CA
SPI_SYS_R1_CLK           R529             1        Q_RES_0402LF-0,5%,1/16W,EMPTY,A
SPI_SYS_R1_MISO          J5               4        SCONN11_9192031111LF-SCONN11_9A
SPI_SYS_R1_MISO          R499             1        Q_RES_0402LF-0,5%,1/16W,CHIP,CA
SPI_SYS_R1_MISO          R585             1        Q_RES_0402LF-0,5%,1/16W,EMPTY,A
SPI_SYS_R1_MOSI          J5               3        SCONN11_9192031111LF-SCONN11_9A
SPI_SYS_R1_MOSI          R498             1        Q_RES_0402LF-0,5%,1/16W,CHIP,CA
SPI_SYS_R1_MOSI          R530             1        Q_RES_0402LF-0,5%,1/16W,EMPTY,A
SPI_SYS_R_CLK            GF1              B11      FCONN168_ME1016810106011-FCONNA
SPI_SYS_R_CLK            R501             2        Q_RES_0402LF-0,5%,1/16W,CHIP,CA
SPI_SYS_R_CLK            R859             1        Q_RES_0402LF-33       ,1%  ,1/A
SPI_SYS_R_MISO           GF1              B14      FCONN168_ME1016810106011-FCONNA
SPI_SYS_R_MISO           R499             2        Q_RES_0402LF-0,5%,1/16W,CHIP,CA
SPI_SYS_R_MISO           R861             1        Q_RES_0402LF-33       ,1%  ,1/A
SPI_SYS_R_MOSI           GF1              B13      FCONN168_ME1016810106011-FCONNA
SPI_SYS_R_MOSI           R498             2        Q_RES_0402LF-0,5%,1/16W,CHIP,CA
SPI_SYS_R_MOSI           R860             1        Q_RES_0402LF-33       ,1%  ,1/A
SPI_SYS_WP_R_IO2         GF1              B15      FCONN168_ME1016810106011-FCONNA
SPI_SYS_WP_R_IO2         R862             1        Q_RES_0402LF-33       ,1%  ,1/A
SPI_TPM_CS_N             GF1              OB12     FCONN168_ME1016810106011-FCONNA
SPI_TPM_CS_N             R594             1        Q_RES_0402LF-33       ,1%  ,1/A
SPI_TPM_CS_N_R           J5               5        SCONN11_9192031111LF-SCONN11_9A
SPI_TPM_CS_N_R           R500             1        Q_RES_0402LF-0,5%,1/16W,CHIP,CA
SPI_TPM_CS_R_N           R500             2        Q_RES_0402LF-0,5%,1/16W,CHIP,CA
SPI_TPM_CS_R_N           R594             2        Q_RES_0402LF-33       ,1%  ,1/A
SW_P1V0_AUX_BST          PC264            1        Q_CAP_0402-0.22UF,16V,10%,X7R,A
SW_P1V0_AUX_BST          PU42             9        NB695GDZ-NB695GD-Z,SMLF,IC,AL0A
SW_P1V0_AUX_FLT          PC261            1        Q_CAP_C0805-10UF,25V,10%,X6S,CA
SW_P1V0_AUX_FLT          PC262            1        Q_CAP_C0805-10UF,25V,10%,X6S,CA
SW_P1V0_AUX_FLT          PC263            1        Q_CAP_0402-0.1UF,25V,10%,X7R,CA
SW_P1V0_AUX_FLT          PL32             2        Q_INDUCTOR_SMLF-BLM18SN220TN1DA
SW_P1V0_AUX_FLT          PU42             1        NB695GDZ-NB695GD-Z,SMLF,IC,AL0A
SW_P1V0_AUX_SW           PC264            2        Q_CAP_0402-0.22UF,16V,10%,X7R,A
SW_P1V0_AUX_SW           PL33             1        Q_INDUCTOR_SMLF-1UH,IND,CV-10BA
SW_P1V0_AUX_SW           PU42             8        NB695GDZ-NB695GD-Z,SMLF,IC,AL0A
SW_P1V2_AUX_BST          PC254            1        Q_CAP_0402-0.22UF,16V,10%,X7R,A
SW_P1V2_AUX_BST          PU41             9        NB695GDZ-NB695GD-Z,SMLF,IC,AL0A
SW_P1V2_AUX_FLT          PC251            1        Q_CAP_C0805-10UF,25V,10%,X6S,CA
SW_P1V2_AUX_FLT          PC252            1        Q_CAP_C0805-10UF,25V,10%,X6S,CA
SW_P1V2_AUX_FLT          PC253            1        Q_CAP_0402-0.1UF,25V,10%,X7R,CA
SW_P1V2_AUX_FLT          PL29             2        Q_INDUCTOR_SMLF-BLM18SN220TN1DA
SW_P1V2_AUX_FLT          PU41             1        NB695GDZ-NB695GD-Z,SMLF,IC,AL0A
SW_P1V2_AUX_SW           PC254            2        Q_CAP_0402-0.22UF,16V,10%,X7R,A
SW_P1V2_AUX_SW           PL31             1        Q_INDUCTOR_SMLF-1UH,IND,CV-10BA
SW_P1V2_AUX_SW           PU41             8        NB695GDZ-NB695GD-Z,SMLF,IC,AL0A
SW_P3V3_AUX_BST          PC224            1        Q_CAP_0402-0.22UF,16V,10%,X7R,A
SW_P3V3_AUX_BST          PU1              10       MPQ8626GDZ-MPQ8626GD-Z,SMLF,ICA
SW_P3V3_AUX_FLT          PC218            1        Q_CAP_C0805-10UF,25V,10%,X6S,CA
SW_P3V3_AUX_FLT          PC219            1        Q_CAP_C0805-10UF,25V,10%,X6S,CA
SW_P3V3_AUX_FLT          PC223            1        Q_CAP_0402-0.1UF,25V,10%,X7R,CA
SW_P3V3_AUX_FLT          PL19             2        Q_INDUCTOR_SMLF-BLM18SN220TN1DA
SW_P3V3_AUX_FLT          PU1              3        MPQ8626GDZ-MPQ8626GD-Z,SMLF,ICA
SW_P3V3_AUX_SW           PC224            2        Q_CAP_0402-0.22UF,16V,10%,X7R,A
SW_P3V3_AUX_SW           PL35             1        Q_INDUCTOR_SMLF-3.3UH/6A,IND,CA
SW_P3V3_AUX_SW           PU1              2        MPQ8626GDZ-MPQ8626GD-Z,SMLF,ICA
SW_P3V3_AUX_SW           PU1              11       MPQ8626GDZ-MPQ8626GD-Z,SMLF,ICA
SW_P5V_AUX_BST           PC216            1        Q_CAP_0402-0.22UF,16V,10%,X7R,A
SW_P5V_AUX_BST           PU38             1        MPQ8633AGLEC807Z-MPQ8633AGLE-CA
SW_P5V_AUX_FLT           PC206            1        Q_CAP_C0805-10UF,25V,10%,X6S,CA
SW_P5V_AUX_FLT           PC207            1        Q_CAP_C0805-10UF,25V,10%,X6S,CA
SW_P5V_AUX_FLT           PC210            1        Q_CAP_0402-0.1UF,25V,10%,X7R,CA
SW_P5V_AUX_FLT           PL4              2        Q_INDUCTOR_SMLF-BLM18SN220TN1DA
SW_P5V_AUX_FLT           PU38             10       MPQ8633AGLEC807Z-MPQ8633AGLE-CA
SW_P5V_AUX_FLT           PU38             21       MPQ8633AGLEC807Z-MPQ8633AGLE-CA
SW_P5V_AUX_SW            PC216            2        Q_CAP_0402-0.22UF,16V,10%,X7R,A
SW_P5V_AUX_SW            PL34             1        Q_INDUCTOR_SMLF-4.7UH,IND,CV-4A
SW_P5V_AUX_SW            PU38             20       MPQ8633AGLEC807Z-MPQ8633AGLE-CA
SYS_BMC_PWRBTN_R_N       R564             1        Q_RES_0402LF-0,5%,1/16W,CHIP,CA
SYS_BMC_PWRBTN_R_N       U5               W24      AST2600A1GP-AST2600A1-GP,SMLF,A
SYS_PWRBTN_N             GF1              A47      FCONN168_ME1016810106011-FCONNA
SYS_PWRBTN_N             R44              2        Q_RES_0402LF-4.7K,5%,1/16W,CHIA
SYS_PWRBTN_N             R80              1        Q_RES_0402LF-33       ,1%  ,1/B
SYS_PWRBTN_N             R564             2        Q_RES_0402LF-0,5%,1/16W,CHIP,CA
TEMP_A0                  R418             2        Q_RES_0402LF-4.7K,5%,1/16W,EMPA
TEMP_A0                  R419             1        Q_RES_0402LF-100,1%,1/16W,CHIPA
TEMP_A0                  U4               7        TMP75AIDGKR-TMP75AIDGKR,SMLF,IA
TEMP_A1                  R416             2        Q_RES_0402LF-4.7K,5%,1/16W,CHIA
TEMP_A1                  R417             1        Q_RES_0402LF-100,1%,1/16W,EMPTA
TEMP_A1                  U4               6        TMP75AIDGKR-TMP75AIDGKR,SMLF,IA
TEMP_A2                  R414             2        Q_RES_0402LF-4.7K,5%,1/16W,EMPA
TEMP_A2                  R415             1        Q_RES_0402LF-100,1%,1/16W,CHIPA
TEMP_A2                  U4               5        TMP75AIDGKR-TMP75AIDGKR,SMLF,IA
U43_CT                   C264             1        Q_CAP_0402-0.1UF,25V,10%,X7R,CA
U43_CT                   R710             2        Q_RES_0402LF-100K,1%,1/16W,CHIA
U43_CT                   U43              4        TPS3808G33DBVR-TPS3808G33DBVR,A
UART_1_SCM_RXD           R760             1        Q_RES_0402LF-33       ,1%  ,1/A
UART_1_SCM_RXD           R766             2        Q_RES_0402LF-33       ,1%  ,1/B
UART_1_SCM_R_RXD         R760             2        Q_RES_0402LF-33       ,1%  ,1/A
UART_1_SCM_R_RXD         U5               B22      AST2600A1GP-AST2600A1-GP,SMLF,A
UART_1_SCM_R_TXD         R122             2        Q_RES_0402LF-33       ,1%  ,1/A
UART_1_SCM_R_TXD         U5               E21      AST2600A1GP-AST2600A1-GP,SMLF,A
UART_1_SCM_TXD           R122             1        Q_RES_0402LF-33       ,1%  ,1/A
UART_1_SCM_TXD           R765             2        Q_RES_0402LF-33       ,1%  ,1/B
UART_2_BMC_RXD           GF1              OB6      FCONN168_ME1016810106011-FCONNA
UART_2_BMC_RXD           R762             1        Q_RES_0402LF-33       ,1%  ,1/A
UART_2_BMC_R_RXD         R762             2        Q_RES_0402LF-33       ,1%  ,1/A
UART_2_BMC_R_RXD         U5               A22      AST2600A1GP-AST2600A1-GP,SMLF,A
UART_2_BMC_R_TXD         R761             2        Q_RES_0402LF-33       ,1%  ,1/A
UART_2_BMC_R_TXD         U5               C21      AST2600A1GP-AST2600A1-GP,SMLF,A
UART_2_BMC_TXD           GF1              OB5      FCONN168_ME1016810106011-FCONNA
UART_2_BMC_TXD           R761             1        Q_RES_0402LF-33       ,1%  ,1/A
UART_BMC_1_RXD           R427             2        Q_RES_0402LF-33       ,1%  ,1/A
UART_BMC_1_RXD           U5               D13      AST2600A1GP-AST2600A1-GP,SMLF,A
UART_BMC_1_RXD_R         R427             1        Q_RES_0402LF-33       ,1%  ,1/A
UART_BMC_1_RXD_R         U3               1        SN74LVC1G3157DCKR-SN74LVC1G315A
UART_BMC_1_TXD           R157             2        Q_RES_0402LF-33       ,1%  ,1/A
UART_BMC_1_TXD           U5               C13      AST2600A1GP-AST2600A1-GP,SMLF,A
UART_BMC_1_TXD_R         R157             1        Q_RES_0402LF-33       ,1%  ,1/A
UART_BMC_1_TXD_R         U2               1        SN74LVC1G3157DCKR-SN74LVC1G315A
UART_BMC_5_RXD           R759             1        Q_RES_0402LF-33       ,1%  ,1/A
UART_BMC_5_RXD           U5               D8       AST2600A1GP-AST2600A1-GP,SMLF,A
UART_BMC_5_RXD_BUF       J6               3        CONN3_210P9103GBR1-CONN3_210-PA
UART_BMC_5_RXD_BUF       U24              3        SN74LVC2G07DCKR_SMLF-SN74LVC2GA
UART_BMC_5_RXD_BUF_R     R72              2        Q_RES_0402LF-4.7K,1%,1/16W,EMPA
UART_BMC_5_RXD_BUF_R     R104             1        Q_RES_0402LF-33       ,1%  ,1/A
UART_BMC_5_RXD_BUF_R     U24              4        SN74LVC2G07DCKR_SMLF-SN74LVC2GA
UART_BMC_5_RXD_R         R104             2        Q_RES_0402LF-33       ,1%  ,1/A
UART_BMC_5_RXD_R         R759             2        Q_RES_0402LF-33       ,1%  ,1/A
UART_BMC_5_RXD_R         R766             1        Q_RES_0402LF-33       ,1%  ,1/B
UART_BMC_5_RXD_R         U3               3        SN74LVC1G3157DCKR-SN74LVC1G315A
UART_BMC_5_TXD           R170             1        Q_RES_0402LF-33       ,1%  ,1/A
UART_BMC_5_TXD           U5               C8       AST2600A1GP-AST2600A1-GP,SMLF,A
UART_BMC_5_TXD_BUF       R67              2        Q_RES_0402LF-4.7K,1%,1/16W,CHIA
UART_BMC_5_TXD_BUF       R102             1        Q_RES_0402LF-33       ,1%  ,1/A
UART_BMC_5_TXD_BUF       U24              6        SN74LVC2G07DCKR_SMLF-SN74LVC2GA
UART_BMC_5_TXD_BUF_R     J6               1        CONN3_210P9103GBR1-CONN3_210-PA
UART_BMC_5_TXD_BUF_R     R102             2        Q_RES_0402LF-33       ,1%  ,1/A
UART_BMC_5_TXD_R         R170             2        Q_RES_0402LF-33       ,1%  ,1/A
UART_BMC_5_TXD_R         R765             1        Q_RES_0402LF-33       ,1%  ,1/B
UART_BMC_5_TXD_R         U2               3        SN74LVC1G3157DCKR-SN74LVC1G315A
UART_BMC_5_TXD_R         U11              2        BAT54C-BAT54C,SMLF,IC,BCBAT54CA
UART_BMC_5_TXD_R         U24              1        SN74LVC2G07DCKR_SMLF-SN74LVC2GA
UNNAMED_231_QFUSE_I153_1 D16              C        SCHOTTKY_AC-RB161SS-20T2R,SMLFA
UNNAMED_231_QFUSE_I153_1 FS1              1        Q_FUSE_SMLF-1.1A/8V,IC,DK110TPA
UNNAMED_231_QFUSE_I153_2 FS1              2        Q_FUSE_SMLF-1.1A/8V,IC,DK110TPA
UNNAMED_231_QFUSE_I153_2 J8               13       SCONN13_502240130C001-SCONN13_A
USB2_01_F_DN             J2               2        CONN9_GSB311131HR-CONN9_GSB311A
USB2_01_F_DN             L23              3        Q_INDUCTOR4P_12-67/320MA,320MAB
USB2_01_F_DN             R385             2        Q_RES_0402LF-0,5%,1/16W,CHIP,CA
USB2_01_F_DN             U38              3        PRTR5V0U2X-PRTR5V0U2X,SMLF,IC,A
USB2_01_F_DP             J2               3        CONN9_GSB311131HR-CONN9_GSB311A
USB2_01_F_DP             L23              2        Q_INDUCTOR4P_12-67/320MA,320MAB
USB2_01_F_DP             R386             2        Q_RES_0402LF-0,5%,1/16W,CHIP,CA
USB2_01_F_DP             U38              2        PRTR5V0U2X-PRTR5V0U2X,SMLF,IC,A
USB2_EXT_DN              L24              4        Q_INDUCTOR4P_12-67/320MA,320MAA
USB2_EXT_DN              R402             2        Q_RES_0201LF-27.4,1%,1/20W,CHIA
USB2_EXT_DP              L24              1        Q_INDUCTOR4P_12-67/320MA,320MAA
USB2_EXT_DP              R403             2        Q_RES_0201LF-27.4,1%,1/20W,CHIA
USB2_EXT_R_DN            J4               2        SCONN5_2UB2141000111F-SCONN5_2A
USB2_EXT_R_DN            L24              3        Q_INDUCTOR4P_12-67/320MA,320MAA
USB2_EXT_R_DN            U18              2        TPD2EUSB30DRTR_SMLF-TPD2EUSB30A
USB2_EXT_R_DP            J4               3        SCONN5_2UB2141000111F-SCONN5_2A
USB2_EXT_R_DP            L24              2        Q_INDUCTOR4P_12-67/320MA,320MAA
USB2_EXT_R_DP            U18              1        TPD2EUSB30DRTR_SMLF-TPD2EUSB30A
USB2_PL2303_EXT_DN       R402             1        Q_RES_0201LF-27.4,1%,1/20W,CHIA
USB2_PL2303_EXT_DN       U17              1        FT234XDR-FT234XD-R,SMLF,IC,AL0A
USB2_PL2303_EXT_DP       R401             2        Q_RES_0201LF-1.5K,1%,1/20W,CHIA
USB2_PL2303_EXT_DP       R403             1        Q_RES_0201LF-27.4,1%,1/20W,CHIA
USB2_PL2303_EXT_DP       U17              12       FT234XDR-FT234XD-R,SMLF,IC,AL0A
USB_FPNL_DN              GF1              B57      FCONN168_ME1016810106011-FCONNA
USB_FPNL_DN              L23              4        Q_INDUCTOR4P_12-67/320MA,320MAB
USB_FPNL_DN              R385             1        Q_RES_0402LF-0,5%,1/16W,CHIP,CA
USB_FPNL_DP              GF1              B56      FCONN168_ME1016810106011-FCONNA
USB_FPNL_DP              L23              1        Q_INDUCTOR4P_12-67/320MA,320MAB
USB_FPNL_DP              R386             1        Q_RES_0402LF-0,5%,1/16W,CHIP,CA
USB_HOST_BMC_A_DN        GF1              B54      FCONN168_ME1016810106011-FCONNA
USB_HOST_BMC_A_DN        R218             2        Q_RES_0402LF-0,5%,1/16W,CHIP,CA
USB_HOST_BMC_A_DP        GF1              B53      FCONN168_ME1016810106011-FCONNA
USB_HOST_BMC_A_DP        R217             2        Q_RES_0402LF-0,5%,1/16W,CHIP,CA
USB_HOST_BMC_A_R_DN      R218             1        Q_RES_0402LF-0,5%,1/16W,CHIP,CA
USB_HOST_BMC_A_R_DN      U5               B4       AST2600A1GP-AST2600A1-GP,SMLF,A
USB_HOST_BMC_A_R_DP      R217             1        Q_RES_0402LF-0,5%,1/16W,CHIP,CA
USB_HOST_BMC_A_R_DP      U5               A4       AST2600A1GP-AST2600A1-GP,SMLF,A
USB_HOST_BMC_B_DN        GF1              B51      FCONN168_ME1016810106011-FCONNA
USB_HOST_BMC_B_DN        R528             2        Q_RES_0402LF-0,5%,1/16W,CHIP,CA
USB_HOST_BMC_B_DP        GF1              B50      FCONN168_ME1016810106011-FCONNA
USB_HOST_BMC_B_DP        R527             2        Q_RES_0402LF-0,5%,1/16W,CHIP,CA
USB_HOST_BMC_B_R_DN      R528             1        Q_RES_0402LF-0,5%,1/16W,CHIP,CA
USB_HOST_BMC_B_R_DN      U5               B6       AST2600A1GP-AST2600A1-GP,SMLF,A
USB_HOST_BMC_B_R_DP      R527             1        Q_RES_0402LF-0,5%,1/16W,CHIP,CA
USB_HOST_BMC_B_R_DP      U5               A6       AST2600A1GP-AST2600A1-GP,SMLF,A
USB_OC0_EN               R376             2        Q_RES_0402LF-4.7K,1%,1/16W,CHIA
USB_OC0_EN               R377             1        Q_RES_0402LF-10K,1%,1/16W,EMPTB
USB_OC0_EN               U10              3        TPS2553DBVR1-TPS2553DBVR-1,SMLA
USB_OC0_ILIM             R378             1        Q_RES_0402LF-20K,1%,1/16W,CHIPA
USB_OC0_ILIM             U10              5        TPS2553DBVR1-TPS2553DBVR-1,SMLA
USB_OC0_REAR_N           R383             2        Q_RES_0402LF-10K,1%,1/16W,CHIPA
USB_OC0_REAR_N           R384             1        Q_RES_0402LF-0,5%,1/16W,CHIP,CA
USB_OC0_REAR_N           U10              4        TPS2553DBVR1-TPS2553DBVR-1,SMLA
USB_OC0_REAR_R_N         R384             2        Q_RES_0402LF-0,5%,1/16W,CHIP,CA
USB_OC0_REAR_R_N         U25              E8       10M02SCU169C8G-10M02SCU169C8G,A
VDDI_U2_EMMC             C11              1        Q_CAP_0402-0.1UF,10V,10%,EMPTYA
VDDI_U2_EMMC             C231             1        Q_CAP_C0402-1UF,6.3V,10%,EMPTYA
VDDI_U2_EMMC             U20              C2       MTFC8GAKAJCN1MWT-MTFC8GAKAJCN-A
VOL_SEN_ALERT_R          R267             2        Q_RES_0402LF-4.7K,5%,1/16W,EMPA
VOL_SEN_ALERT_R          U5               K23      AST2600A1GP-AST2600A1-GP,SMLF,A
VOL_SEN_ALERT_R          U25              N2       10M02SCU169C8G-10M02SCU169C8G,A
V_BMC_DDC_LS_GATE        Q2               2        MOSFET_NCH_DUAL-2N7002KDW,SMLFA
V_BMC_DDC_LS_GATE        Q2               5        MOSFET_NCH_DUAL-2N7002KDW,SMLFA
V_BMC_DDC_LS_GATE        R86              2        Q_RES_0402LF-0,5%,1/16W,CHIP,CA
V_BMC_DDC_SCL            Q2               4        MOSFET_NCH_DUAL-2N7002KDW,SMLFA
V_BMC_DDC_SCL            R32              2        Q_RES_0402LF-4.7K,1%,1/16W,CHIA
V_BMC_DDC_SCL            U5               B8       AST2600A1GP-AST2600A1-GP,SMLF,A
V_BMC_DDC_SDA            Q2               1        MOSFET_NCH_DUAL-2N7002KDW,SMLFA
V_BMC_DDC_SDA            R31              2        Q_RES_0402LF-4.7K,1%,1/16W,CHIA
V_BMC_DDC_SDA            U5               A8       AST2600A1GP-AST2600A1-GP,SMLF,A
V_BMC_LS_DDC_SCL         Q2               3        MOSFET_NCH_DUAL-2N7002KDW,SMLFA
V_BMC_LS_DDC_SCL         R28              1        Q_RES_0402LF-33       ,1%  ,1/A
V_BMC_LS_DDC_SCL         R92              2        Q_RES_0402LF-2.2K ,5%,1/16W,CHA
V_BMC_LS_DDC_SCL_R       C214             1        Q_CAP_0402-100PF,50V,5%,EMPTY,A
V_BMC_LS_DDC_SCL_R       J8               12       SCONN13_502240130C001-SCONN13_A
V_BMC_LS_DDC_SCL_R       R16              1        Q_RES_0402LF-2.21K    ,1%  ,1/A
V_BMC_LS_DDC_SCL_R       R28              2        Q_RES_0402LF-33       ,1%  ,1/A
V_BMC_LS_DDC_SCL_R       U34              3        TPD4E001DBVR-TPD4E001DBVR,SMLFA
V_BMC_LS_DDC_SDA         Q2               6        MOSFET_NCH_DUAL-2N7002KDW,SMLFA
V_BMC_LS_DDC_SDA         R29              1        Q_RES_0402LF-33       ,1%  ,1/A
V_BMC_LS_DDC_SDA         R91              2        Q_RES_0402LF-2.2K ,5%,1/16W,CHA
V_BMC_LS_DDC_SDA_R       C213             1        Q_CAP_0402-100PF,50V,5%,EMPTY,A
V_BMC_LS_DDC_SDA_R       J8               11       SCONN13_502240130C001-SCONN13_A
V_BMC_LS_DDC_SDA_R       R17              1        Q_RES_0402LF-2.21K    ,1%  ,1/A
V_BMC_LS_DDC_SDA_R       R29              2        Q_RES_0402LF-33       ,1%  ,1/A
V_BMC_LS_DDC_SDA_R       U34              1        TPD4E001DBVR-TPD4E001DBVR,SMLFA
V_DACB                   C207             1        Q_CAP_0402-10PF,50V,1%,NPO,TMPA
V_DACB                   L28              1        Q_INDUCTOR_SMLF-47/300MA,IND,CA
V_DACB                   R24              2        Q_RES_0402LF-0,5%,1/16W,CHIP,CA
V_DACB_IO                C210             1        Q_CAP_C0402-33PF,50V,1%,C0G,CHA
V_DACB_IO                J8               5        SCONN13_502240130C001-SCONN13_A
V_DACB_IO                L28              2        Q_INDUCTOR_SMLF-47/300MA,IND,CA
V_DACB_IO                R87              1        Q_RES_0402LF-150,1%,1/16W,CHIPA
V_DACB_IO                U35              1        TPD4E001DBVR-TPD4E001DBVR,SMLFA
V_DACB_R                 R22              1        Q_RES_0402LF-150,1%,1/16W,CHIPA
V_DACB_R                 R24              1        Q_RES_0402LF-0,5%,1/16W,CHIP,CA
V_DACB_R                 U5               AD21     AST2600A1GP-AST2600A1-GP,SMLF,A
V_DACG                   C206             1        Q_CAP_0402-10PF,50V,1%,NPO,TMPA
V_DACG                   L29              1        Q_INDUCTOR_SMLF-47/300MA,IND,CA
V_DACG                   R21              2        Q_RES_0402LF-0,5%,1/16W,CHIP,CA
V_DACG_IO                C209             1        Q_CAP_C0402-33PF,50V,1%,C0G,CHA
V_DACG_IO                J8               3        SCONN13_502240130C001-SCONN13_A
V_DACG_IO                L29              2        Q_INDUCTOR_SMLF-47/300MA,IND,CA
V_DACG_IO                R88              1        Q_RES_0402LF-150,1%,1/16W,CHIPA
V_DACG_IO                U35              3        TPD4E001DBVR-TPD4E001DBVR,SMLFA
V_DACG_R                 R21              1        Q_RES_0402LF-0,5%,1/16W,CHIP,CA
V_DACG_R                 R23              1        Q_RES_0402LF-150,1%,1/16W,CHIPA
V_DACG_R                 U5               AE21     AST2600A1GP-AST2600A1-GP,SMLF,A
V_DACR                   C205             1        Q_CAP_0402-10PF,50V,1%,NPO,TMPA
V_DACR                   L30              1        Q_INDUCTOR_SMLF-47/300MA,IND,CA
V_DACR                   R26              2        Q_RES_0402LF-0,5%,1/16W,CHIP,CA
V_DACR_IO                C208             1        Q_CAP_C0402-33PF,50V,1%,C0G,CHA
V_DACR_IO                J8               1        SCONN13_502240130C001-SCONN13_A
V_DACR_IO                L30              2        Q_INDUCTOR_SMLF-47/300MA,IND,CA
V_DACR_IO                R89              1        Q_RES_0402LF-150,1%,1/16W,CHIPA
V_DACR_IO                U35              4        TPD4E001DBVR-TPD4E001DBVR,SMLFA
V_DACR_R                 R25              1        Q_RES_0402LF-150,1%,1/16W,CHIPA
V_DACR_R                 R26              1        Q_RES_0402LF-0,5%,1/16W,CHIP,CA
V_DACR_R                 U5               AF21     AST2600A1GP-AST2600A1-GP,SMLF,A
V_VGAHS                  R19              2        Q_RES_0402LF-0,5%,1/16W,CHIP,CA
V_VGAHS                  U33              2        74HC1G126GW-74HC1G126GW,SMLF,IA
V_VGAHS_BUF              C211             1        Q_CAP_0402-10PF,50V,5%,COG,CH0A
V_VGAHS_BUF              J8               9        SCONN13_502240130C001-SCONN13_A
V_VGAHS_BUF              R85              2        Q_RES_0402LF-33       ,1%  ,1/A
V_VGAHS_BUF              U34              6        TPD4E001DBVR-TPD4E001DBVR,SMLFA
V_VGAHS_BUF_R            R85              1        Q_RES_0402LF-33       ,1%  ,1/A
V_VGAHS_BUF_R            U33              4        74HC1G126GW-74HC1G126GW,SMLF,IA
V_VGAHS_R                R19              1        Q_RES_0402LF-0,5%,1/16W,CHIP,CA
V_VGAHS_R                U5               B14      AST2600A1GP-AST2600A1-GP,SMLF,A
V_VGAVS                  R20              2        Q_RES_0402LF-0,5%,1/16W,CHIP,CA
V_VGAVS                  U26              2        74HC1G126GW-74HC1G126GW,SMLF,IA
V_VGAVS_BUF              C212             1        Q_CAP_0402-10PF,50V,5%,COG,CH0A
V_VGAVS_BUF              J8               7        SCONN13_502240130C001-SCONN13_A
V_VGAVS_BUF              R84              2        Q_RES_0402LF-33       ,1%  ,1/A
V_VGAVS_BUF              U34              4        TPD4E001DBVR-TPD4E001DBVR,SMLFA
V_VGAVS_BUF_R            R84              1        Q_RES_0402LF-33       ,1%  ,1/A
V_VGAVS_BUF_R            U26              4        74HC1G126GW-74HC1G126GW,SMLF,IA
V_VGAVS_R                R20              1        Q_RES_0402LF-0,5%,1/16W,CHIP,CA
V_VGAVS_R                U5               C14      AST2600A1GP-AST2600A1-GP,SMLF,A
XTAL_PHY_XI              R286             2        Q_RES_0402LF-22,1%,1/16W,CHIP,A
XTAL_PHY_XI              U7               8        BCM54612EB1KMLG-BCM54612EB1KMLA
XTAL_PHY_XI_R            C141             1        Q_CAP_C0402-12PF,50V,5%,C0G,CHA
XTAL_PHY_XI_R            R286             1        Q_RES_0402LF-22,1%,1/16W,CHIP,A
XTAL_PHY_XI_R            Y1               1        Q_XTAL_4P_13BI_24GND-25MHZ,SMLA
XTAL_PHY_XO              R288             2        Q_RES_0402LF-22,1%,1/16W,CHIP,A
XTAL_PHY_XO              U7               7        BCM54612EB1KMLG-BCM54612EB1KMLA
XTAL_PHY_XO_R            C145             1        Q_CAP_C0402-12PF,50V,5%,C0G,CHA
XTAL_PHY_XO_R            R288             1        Q_RES_0402LF-22,1%,1/16W,CHIP,A
XTAL_PHY_XO_R            Y1               3        Q_XTAL_4P_13BI_24GND-25MHZ,SMLA
END CONCISE NET LIST
